G04 ================== begin FILE IDENTIFICATION RECORD ==================*
G04 Layout Name:  12432-1.brd*
G04 Film Name:    DRILL*
G04 File Format:  Gerber RS274X*
G04 File Origin:  Cadence Allegro 16.2-S037*
G04 Origin Date:  Wed Oct 17 10:59:45 2012*
G04 *
G04 Layer:  MANUFACTURING/NCLEGEND-1-8*
G04 Layer:  MANUFACTURING/DRILL SIZE*
G04 Layer:  DRAWING FORMAT/LAYER_PCB_STORY*
G04 Layer:  DRAWING FORMAT/LAYER_DRILL*
G04 Layer:  BOARD GEOMETRY/PANEL_OUTLINE*
G04 *
G04 Offset:    (0.00 0.00)*
G04 Mirror:    No*
G04 Mode:      Positive*
G04 Rotation:  0*
G04 FullContactRelief:  No*
G04 UndefLineWidth:     6.00*
G04 ================== end FILE IDENTIFICATION RECORD ====================*
%FSLAX35Y35*MOIN*%
%IR0*IPPOS*OFA0.00000B0.00000*MIA0B0*SFA1.00000B1.00000*%
%AMMACRO14*
1,1,.006,.006,0.0*
20,1,.006,.006,0.0,-.006,0.0,0.0*
1,1,.006,-.006,0.0*
1,1,.006,0.0,.006*
20,1,.006,0.0,.006,0.0,-.006,0.0*
1,1,.006,0.0,-.006*
1,1,.006,.003,0.0*
20,1,.006,.003,0.0,.003,.006,0.0*
1,1,.006,.003,.006*
20,1,.006,.003,.006,.0018,.0048,0.0*
1,1,.006,.0018,.0048*
1,1,.006,.0018,0.0*
20,1,.006,.0018,0.0,.0042,0.0,0.0*
1,1,.006,.0042,0.0*
%
%ADD14MACRO14*%
%AMMACRO11*
1,1,.006,.008,.008*
20,1,.006,.008,.008,.008,-.008,0.0*
1,1,.006,.008,-.008*
20,1,.006,.008,-.008,-.008,-.008,0.0*
1,1,.006,-.008,-.008*
20,1,.006,-.008,-.008,-.008,.008,0.0*
1,1,.006,-.008,.008*
20,1,.006,-.008,.008,.008,.008,0.0*
1,1,.006,.008,.008*
1,1,.006,-.00253,.00267*
20,1,.006,-.00253,.00267,-.00173,.00347,0.0*
1,1,.006,-.00173,.00347*
20,1,.006,-.00173,.00347,-.0008,.00387,0.0*
1,1,.006,-.0008,.00387*
20,1,.006,-.0008,.00387,.00027,.004,0.0*
1,1,.006,.00027,.004*
20,1,.006,.00027,.004,.0016,.00373,0.0*
1,1,.006,.0016,.00373*
20,1,.006,.0016,.00373,.00253,.00307,0.0*
1,1,.006,.00253,.00307*
20,1,.006,.00253,.00307,.0028,.00227,0.0*
1,1,.006,.0028,.00227*
20,1,.006,.0028,.00227,.00267,.00147,0.0*
1,1,.006,.00267,.00147*
20,1,.006,.00267,.00147,.00213,.0008,0.0*
1,1,.006,.00213,.0008*
20,1,.006,.00213,.0008,-.00053,-.00053,0.0*
1,1,.006,-.00053,-.00053*
20,1,.006,-.00053,-.00053,-.00173,-.00147,0.0*
1,1,.006,-.00173,-.00147*
20,1,.006,-.00173,-.00147,-.00253,-.0028,0.0*
1,1,.006,-.00253,-.0028*
20,1,.006,-.00253,-.0028,-.0028,-.004,0.0*
1,1,.006,-.0028,-.004*
20,1,.006,-.0028,-.004,.0028,-.004,0.0*
1,1,.006,.0028,-.004*
%
%ADD11MACRO11*%
%AMMACRO16*
1,1,.006,.015119,-.0365*
20,1,.006,.015119,-.0365,-.015119,-.0365,0.0*
1,1,.006,-.015119,-.0365*
20,1,.006,-.015119,-.0365,-.0365,-.015119,0.0*
1,1,.006,-.0365,-.015119*
20,1,.006,-.0365,-.015119,-.0365,.015119,0.0*
1,1,.006,-.0365,.015119*
20,1,.006,-.0365,.015119,-.015119,.0365,0.0*
1,1,.006,-.015119,.0365*
20,1,.006,-.015119,.0365,.015119,.0365,0.0*
1,1,.006,.015119,.0365*
20,1,.006,.015119,.0365,.0365,.015119,0.0*
1,1,.006,.0365,.015119*
20,1,.006,.0365,.015119,.0365,-.015119,0.0*
1,1,.006,.0365,-.015119*
20,1,.006,.0365,-.015119,.015119,-.0365,0.0*
1,1,.006,.015119,-.0365*
1,1,.006,-.01338,-.01278*
20,1,.006,-.01338,-.01278,-.00973,-.01582,0.0*
1,1,.006,-.00973,-.01582*
20,1,.006,-.00973,-.01582,-.00548,-.01764,0.0*
1,1,.006,-.00548,-.01764*
20,1,.006,-.00548,-.01764,0.0,-.01825,0.0*
1,1,.006,0.0,-.01825*
20,1,.006,0.0,-.01825,.00548,-.01703,0.0*
1,1,.006,.00548,-.01703*
20,1,.006,.00548,-.01703,.00973,-.0146,0.0*
1,1,.006,.00973,-.0146*
20,1,.006,.00973,-.0146,.01278,-.01034,0.0*
1,1,.006,.01278,-.01034*
20,1,.006,.01278,-.01034,.01338,-.00548,0.0*
1,1,.006,.01338,-.00548*
20,1,.006,.01338,-.00548,.01217,-.00061,0.0*
1,1,.006,.01217,-.00061*
20,1,.006,.01217,-.00061,.00912,.00243,0.0*
1,1,.006,.00912,.00243*
20,1,.006,.00912,.00243,.00487,.00487,0.0*
1,1,.006,.00487,.00487*
20,1,.006,.00487,.00487,.00061,.00547,0.0*
1,1,.006,.00061,.00547*
20,1,.006,.00061,.00547,-.00365,.00487,0.0*
1,1,.006,-.00365,.00487*
20,1,.006,-.00365,.00487,-.00912,.00243,0.0*
1,1,.006,-.00912,.00243*
20,1,.006,-.00912,.00243,-.0073,.01825,0.0*
1,1,.006,-.0073,.01825*
20,1,.006,-.0073,.01825,.00912,.01825,0.0*
1,1,.006,.00912,.01825*
%
%ADD16MACRO16*%
%AMMACRO10*
1,1,.006,.043,0.0*
20,1,.006,.043,0.0,0.0,-.043,0.0*
1,1,.006,0.0,-.043*
20,1,.006,0.0,-.043,-.043,0.0,0.0*
1,1,.006,-.043,0.0*
20,1,.006,-.043,0.0,0.0,.043,0.0*
1,1,.006,0.0,.043*
20,1,.006,0.0,.043,.043,0.0,0.0*
1,1,.006,.043,0.0*
1,1,.006,-.01362,-.00358*
20,1,.006,-.01362,-.00358,-.0086,.00143,0.0*
1,1,.006,-.0086,.00143*
20,1,.006,-.0086,.00143,-.0043,.0043,0.0*
1,1,.006,-.0043,.0043*
20,1,.006,-.0043,.0043,.00143,.00573,0.0*
1,1,.006,.00143,.00573*
20,1,.006,.00143,.00573,.00645,.0043,0.0*
1,1,.006,.00645,.0043*
20,1,.006,.00645,.0043,.01003,.00143,0.0*
1,1,.006,.01003,.00143*
20,1,.006,.01003,.00143,.0129,-.00287,0.0*
1,1,.006,.0129,-.00287*
20,1,.006,.0129,-.00287,.01362,-.00788,0.0*
1,1,.006,.01362,-.00788*
20,1,.006,.01362,-.00788,.0129,-.01218,0.0*
1,1,.006,.0129,-.01218*
20,1,.006,.0129,-.01218,.01003,-.01648,0.0*
1,1,.006,.01003,-.01648*
20,1,.006,.01003,-.01648,.00573,-.02007,0.0*
1,1,.006,.00573,-.02007*
20,1,.006,.00573,-.02007,.00072,-.0215,0.0*
1,1,.006,.00072,-.0215*
20,1,.006,.00072,-.0215,-.00502,-.02007,0.0*
1,1,.006,-.00502,-.02007*
20,1,.006,-.00502,-.02007,-.01003,-.01577,0.0*
1,1,.006,-.01003,-.01577*
20,1,.006,-.01003,-.01577,-.0129,-.00932,0.0*
1,1,.006,-.0129,-.00932*
20,1,.006,-.0129,-.00932,-.01362,-.00215,0.0*
1,1,.006,-.01362,-.00215*
20,1,.006,-.01362,-.00215,-.01218,.00717,0.0*
1,1,.006,-.01218,.00717*
20,1,.006,-.01218,.00717,-.01003,.01218,0.0*
1,1,.006,-.01003,.01218*
20,1,.006,-.01003,.01218,-.00645,.0172,0.0*
1,1,.006,-.00645,.0172*
20,1,.006,-.00645,.0172,-.00143,.02078,0.0*
1,1,.006,-.00143,.02078*
20,1,.006,-.00143,.02078,.00358,.0215,0.0*
1,1,.006,.00358,.0215*
20,1,.006,.00358,.0215,.0086,.02007,0.0*
1,1,.006,.0086,.02007*
20,1,.006,.0086,.02007,.01218,.01648,0.0*
1,1,.006,.01218,.01648*
%
%ADD10MACRO10*%
%AMMACRO12*
1,1,.006,.07,0.0*
20,1,.006,.07,0.0,.035,.060622,0.0*
1,1,.006,.035,.060622*
20,1,.006,.035,.060622,-.035,.060622,0.0*
1,1,.006,-.035,.060622*
20,1,.006,-.035,.060622,-.07,0.0,0.0*
1,1,.006,-.07,0.0*
20,1,.006,-.07,0.0,-.035,-.060622,0.0*
1,1,.006,-.035,-.060622*
20,1,.006,-.035,-.060622,.035,-.060622,0.0*
1,1,.006,.035,-.060622*
20,1,.006,.035,-.060622,.07,0.0,0.0*
1,1,.006,.07,0.0*
1,1,.006,-.02567,-.021*
20,1,.006,-.02567,-.021,-.01867,-.02917,0.0*
1,1,.006,-.01867,-.02917*
20,1,.006,-.01867,-.02917,-.00933,-.03383,0.0*
1,1,.006,-.00933,-.03383*
20,1,.006,-.00933,-.03383,.00117,-.035,0.0*
1,1,.006,.00117,-.035*
20,1,.006,.00117,-.035,.0105,-.03383,0.0*
1,1,.006,.0105,-.03383*
20,1,.006,.0105,-.03383,.01983,-.028,0.0*
1,1,.006,.01983,-.028*
20,1,.006,.01983,-.028,.02567,-.021,0.0*
1,1,.006,.02567,-.021*
20,1,.006,.02567,-.021,.02683,-.014,0.0*
1,1,.006,.02683,-.014*
20,1,.006,.02683,-.014,.0245,-.00584,0.0*
1,1,.006,.0245,-.00584*
20,1,.006,.0245,-.00584,.01633,0.0,0.0*
1,1,.006,.01633,0.0*
20,1,.006,.01633,0.0,.00817,.00233,0.0*
1,1,.006,.00817,.00233*
20,1,.006,.00817,.00233,-.00233,.00233,0.0*
1,1,.006,-.00233,.00233*
1,1,.006,.00817,.00233*
20,1,.006,.00817,.00233,.01517,.00583,0.0*
1,1,.006,.01517,.00583*
20,1,.006,.01517,.00583,.021,.01167,0.0*
1,1,.006,.021,.01167*
20,1,.006,.021,.01167,.02333,.01867,0.0*
1,1,.006,.02333,.01867*
20,1,.006,.02333,.01867,.021,.02567,0.0*
1,1,.006,.021,.02567*
20,1,.006,.021,.02567,.01517,.0315,0.0*
1,1,.006,.01517,.0315*
20,1,.006,.01517,.0315,.00467,.035,0.0*
1,1,.006,.00467,.035*
20,1,.006,.00467,.035,-.00583,.03383,0.0*
1,1,.006,-.00583,.03383*
20,1,.006,-.00583,.03383,-.01633,.02917,0.0*
1,1,.006,-.01633,.02917*
%
%ADD12MACRO12*%
%AMMACRO18*
1,1,.006,0.0,.073*
20,1,.006,0.0,.073,0.0,.073,0.0*
1,1,.006,0.0,.073*
20,1,.006,0.0,.073,.012676,.071891,0.0*
1,1,.006,.012676,.071891*
20,1,.006,.012676,.071891,.024967,.068598,0.0*
1,1,.006,.024967,.068598*
20,1,.006,.024967,.068598,.0365,.06322,0.0*
1,1,.006,.0365,.06322*
20,1,.006,.0365,.06322,.046923,.055921,0.0*
1,1,.006,.046923,.055921*
20,1,.006,.046923,.055921,.055921,.046923,0.0*
1,1,.006,.055921,.046923*
20,1,.006,.055921,.046923,.06322,.0365,0.0*
1,1,.006,.06322,.0365*
20,1,.006,.06322,.0365,.068598,.024967,0.0*
1,1,.006,.068598,.024967*
20,1,.006,.068598,.024967,.071891,.012676,0.0*
1,1,.006,.071891,.012676*
20,1,.006,.071891,.012676,.073,0.0,0.0*
1,1,.006,.073,0.0*
20,1,.006,.073,0.0,.071891,-.012676,0.0*
1,1,.006,.071891,-.012676*
20,1,.006,.071891,-.012676,.068598,-.024967,0.0*
1,1,.006,.068598,-.024967*
20,1,.006,.068598,-.024967,.06322,-.0365,0.0*
1,1,.006,.06322,-.0365*
20,1,.006,.06322,-.0365,.055921,-.046923,0.0*
1,1,.006,.055921,-.046923*
20,1,.006,.055921,-.046923,.046923,-.055921,0.0*
1,1,.006,.046923,-.055921*
20,1,.006,.046923,-.055921,.0365,-.06322,0.0*
1,1,.006,.0365,-.06322*
20,1,.006,.0365,-.06322,.024967,-.068598,0.0*
1,1,.006,.024967,-.068598*
20,1,.006,.024967,-.068598,.012676,-.071891,0.0*
1,1,.006,.012676,-.071891*
20,1,.006,.012676,-.071891,0.0,-.073,0.0*
1,1,.006,0.0,-.073*
20,1,.006,0.0,-.073,0.0,-.073,0.0*
1,1,.006,0.0,-.073*
20,1,.006,0.0,-.073,-.012676,-.071891,0.0*
1,1,.006,-.012676,-.071891*
20,1,.006,-.012676,-.071891,-.024967,-.068598,0.0*
1,1,.006,-.024967,-.068598*
20,1,.006,-.024967,-.068598,-.0365,-.06322,0.0*
1,1,.006,-.0365,-.06322*
20,1,.006,-.0365,-.06322,-.046923,-.055921,0.0*
1,1,.006,-.046923,-.055921*
20,1,.006,-.046923,-.055921,-.055921,-.046923,0.0*
1,1,.006,-.055921,-.046923*
20,1,.006,-.055921,-.046923,-.06322,-.0365,0.0*
1,1,.006,-.06322,-.0365*
20,1,.006,-.06322,-.0365,-.068598,-.024967,0.0*
1,1,.006,-.068598,-.024967*
20,1,.006,-.068598,-.024967,-.071891,-.012676,0.0*
1,1,.006,-.071891,-.012676*
20,1,.006,-.071891,-.012676,-.073,0.0,0.0*
1,1,.006,-.073,0.0*
20,1,.006,-.073,0.0,-.071891,.012676,0.0*
1,1,.006,-.071891,.012676*
20,1,.006,-.071891,.012676,-.068598,.024967,0.0*
1,1,.006,-.068598,.024967*
20,1,.006,-.068598,.024967,-.06322,.0365,0.0*
1,1,.006,-.06322,.0365*
20,1,.006,-.06322,.0365,-.055921,.046923,0.0*
1,1,.006,-.055921,.046923*
20,1,.006,-.055921,.046923,-.046923,.055921,0.0*
1,1,.006,-.046923,.055921*
20,1,.006,-.046923,.055921,-.0365,.06322,0.0*
1,1,.006,-.0365,.06322*
20,1,.006,-.0365,.06322,-.024967,.068598,0.0*
1,1,.006,-.024967,.068598*
20,1,.006,-.024967,.068598,-.012676,.071891,0.0*
1,1,.006,-.012676,.071891*
20,1,.006,-.012676,.071891,0.0,.073,0.0*
1,1,.006,0.0,.073*
1,1,.006,0.0,-.0365*
20,1,.006,0.0,-.0365,.00852,-.03528,0.0*
1,1,.006,.00852,-.03528*
20,1,.006,.00852,-.03528,.01825,-.03163,0.0*
1,1,.006,.01825,-.03163*
20,1,.006,.01825,-.03163,.02433,-.02555,0.0*
1,1,.006,.02433,-.02555*
20,1,.006,.02433,-.02555,.02677,-.01703,0.0*
1,1,.006,.02677,-.01703*
20,1,.006,.02677,-.01703,.02433,-.00852,0.0*
1,1,.006,.02433,-.00852*
20,1,.006,.02433,-.00852,.01703,-.00122,0.0*
1,1,.006,.01703,-.00122*
20,1,.006,.01703,-.00122,.00608,.00243,0.0*
1,1,.006,.00608,.00243*
20,1,.006,.00608,.00243,-.00608,.00243,0.0*
1,1,.006,-.00608,.00243*
20,1,.006,-.00608,.00243,-.01338,.00487,0.0*
1,1,.006,-.01338,.00487*
20,1,.006,-.01338,.00487,-.01947,.01095,0.0*
1,1,.006,-.01947,.01095*
20,1,.006,-.01947,.01095,-.0219,.01947,0.0*
1,1,.006,-.0219,.01947*
20,1,.006,-.0219,.01947,-.01825,.02798,0.0*
1,1,.006,-.01825,.02798*
20,1,.006,-.01825,.02798,-.00973,.03407,0.0*
1,1,.006,-.00973,.03407*
20,1,.006,-.00973,.03407,0.0,.0365,0.0*
1,1,.006,0.0,.0365*
20,1,.006,0.0,.0365,.00973,.03407,0.0*
1,1,.006,.00973,.03407*
20,1,.006,.00973,.03407,.01825,.02798,0.0*
1,1,.006,.01825,.02798*
20,1,.006,.01825,.02798,.0219,.01947,0.0*
1,1,.006,.0219,.01947*
20,1,.006,.0219,.01947,.01947,.01095,0.0*
1,1,.006,.01947,.01095*
20,1,.006,.01947,.01095,.01338,.00487,0.0*
1,1,.006,.01338,.00487*
20,1,.006,.01338,.00487,.00608,.00243,0.0*
1,1,.006,.00608,.00243*
20,1,.006,.00608,.00243,-.00608,.00243,0.0*
1,1,.006,-.00608,.00243*
20,1,.006,-.00608,.00243,-.01703,-.00122,0.0*
1,1,.006,-.01703,-.00122*
20,1,.006,-.01703,-.00122,-.02433,-.00852,0.0*
1,1,.006,-.02433,-.00852*
20,1,.006,-.02433,-.00852,-.02677,-.01703,0.0*
1,1,.006,-.02677,-.01703*
20,1,.006,-.02677,-.01703,-.02433,-.02555,0.0*
1,1,.006,-.02433,-.02555*
20,1,.006,-.02433,-.02555,-.01825,-.03163,0.0*
1,1,.006,-.01825,-.03163*
20,1,.006,-.01825,-.03163,-.00852,-.03528,0.0*
1,1,.006,-.00852,-.03528*
20,1,.006,-.00852,-.03528,0.0,-.0365,0.0*
1,1,.006,0.0,-.0365*
%
%ADD18MACRO18*%
%AMMACRO15*
1,1,.006,-.0215,.016*
20,1,.006,-.0215,.016,.0215,.016,0.0*
1,1,.006,.0215,.016*
20,1,.006,.0215,.016,.024278,.015757,0.0*
1,1,.006,.024278,.015757*
20,1,.006,.024278,.015757,.026972,.015035,0.0*
1,1,.006,.026972,.015035*
20,1,.006,.026972,.015035,.0295,.013856,0.0*
1,1,.006,.0295,.013856*
20,1,.006,.0295,.013856,.031785,.012257,0.0*
1,1,.006,.031785,.012257*
20,1,.006,.031785,.012257,.033757,.010285,0.0*
1,1,.006,.033757,.010285*
20,1,.006,.033757,.010285,.035356,.008,0.0*
1,1,.006,.035356,.008*
20,1,.006,.035356,.008,.036535,.005472,0.0*
1,1,.006,.036535,.005472*
20,1,.006,.036535,.005472,.037257,.002778,0.0*
1,1,.006,.037257,.002778*
20,1,.006,.037257,.002778,.0375,0.0,0.0*
1,1,.006,.0375,0.0*
20,1,.006,.0375,0.0,.037257,-.002778,0.0*
1,1,.006,.037257,-.002778*
20,1,.006,.037257,-.002778,.036535,-.005472,0.0*
1,1,.006,.036535,-.005472*
20,1,.006,.036535,-.005472,.035356,-.008,0.0*
1,1,.006,.035356,-.008*
20,1,.006,.035356,-.008,.033757,-.010285,0.0*
1,1,.006,.033757,-.010285*
20,1,.006,.033757,-.010285,.031785,-.012257,0.0*
1,1,.006,.031785,-.012257*
20,1,.006,.031785,-.012257,.0295,-.013856,0.0*
1,1,.006,.0295,-.013856*
20,1,.006,.0295,-.013856,.026972,-.015035,0.0*
1,1,.006,.026972,-.015035*
20,1,.006,.026972,-.015035,.024278,-.015757,0.0*
1,1,.006,.024278,-.015757*
20,1,.006,.024278,-.015757,.0215,-.016,0.0*
1,1,.006,.0215,-.016*
20,1,.006,.0215,-.016,-.0215,-.016,0.0*
1,1,.006,-.0215,-.016*
20,1,.006,-.0215,-.016,-.024278,-.015757,0.0*
1,1,.006,-.024278,-.015757*
20,1,.006,-.024278,-.015757,-.026972,-.015035,0.0*
1,1,.006,-.026972,-.015035*
20,1,.006,-.026972,-.015035,-.0295,-.013856,0.0*
1,1,.006,-.0295,-.013856*
20,1,.006,-.0295,-.013856,-.031785,-.012257,0.0*
1,1,.006,-.031785,-.012257*
20,1,.006,-.031785,-.012257,-.033757,-.010285,0.0*
1,1,.006,-.033757,-.010285*
20,1,.006,-.033757,-.010285,-.035356,-.008,0.0*
1,1,.006,-.035356,-.008*
20,1,.006,-.035356,-.008,-.036535,-.005472,0.0*
1,1,.006,-.036535,-.005472*
20,1,.006,-.036535,-.005472,-.037257,-.002778,0.0*
1,1,.006,-.037257,-.002778*
20,1,.006,-.037257,-.002778,-.0375,0.0,0.0*
1,1,.006,-.0375,0.0*
20,1,.006,-.0375,0.0,-.037257,.002778,0.0*
1,1,.006,-.037257,.002778*
20,1,.006,-.037257,.002778,-.036535,.005472,0.0*
1,1,.006,-.036535,.005472*
20,1,.006,-.036535,.005472,-.035356,.008,0.0*
1,1,.006,-.035356,.008*
20,1,.006,-.035356,.008,-.033757,.010285,0.0*
1,1,.006,-.033757,.010285*
20,1,.006,-.033757,.010285,-.031785,.012257,0.0*
1,1,.006,-.031785,.012257*
20,1,.006,-.031785,.012257,-.0295,.013856,0.0*
1,1,.006,-.0295,.013856*
20,1,.006,-.0295,.013856,-.026972,.015035,0.0*
1,1,.006,-.026972,.015035*
20,1,.006,-.026972,.015035,-.024278,.015757,0.0*
1,1,.006,-.024278,.015757*
20,1,.006,-.024278,.015757,-.0215,.016,0.0*
1,1,.006,-.0215,.016*
1,1,.006,-.00453,-.00613*
20,1,.006,-.00453,-.00613,-.00267,-.00747,0.0*
1,1,.006,-.00267,-.00747*
20,1,.006,-.00267,-.00747,-.00053,-.008,0.0*
1,1,.006,-.00053,-.008*
20,1,.006,-.00053,-.008,.0016,-.00747,0.0*
1,1,.006,.0016,-.00747*
20,1,.006,.0016,-.00747,.00347,-.00587,0.0*
1,1,.006,.00347,-.00587*
20,1,.006,.00347,-.00587,.0048,-.00347,0.0*
1,1,.006,.0048,-.00347*
20,1,.006,.0048,-.00347,.00533,-.00107,0.0*
1,1,.006,.00533,-.00107*
20,1,.006,.00533,-.00107,.00533,.00187,0.0*
1,1,.006,.00533,.00187*
20,1,.006,.00533,.00187,.0048,.00427,0.0*
1,1,.006,.0048,.00427*
20,1,.006,.0048,.00427,.00347,.0064,0.0*
1,1,.006,.00347,.0064*
20,1,.006,.00347,.0064,.00187,.00747,0.0*
1,1,.006,.00187,.00747*
20,1,.006,.00187,.00747,0.0,.008,0.0*
1,1,.006,0.0,.008*
20,1,.006,0.0,.008,-.00213,.00747,0.0*
1,1,.006,-.00213,.00747*
20,1,.006,-.00213,.00747,-.00373,.0064,0.0*
1,1,.006,-.00373,.0064*
20,1,.006,-.00373,.0064,-.0048,.0048,0.0*
1,1,.006,-.0048,.0048*
20,1,.006,-.0048,.0048,-.00533,.00267,0.0*
1,1,.006,-.00533,.00267*
20,1,.006,-.00533,.00267,-.0048,.0008,0.0*
1,1,.006,-.0048,.0008*
20,1,.006,-.0048,.0008,-.00347,-.00107,0.0*
1,1,.006,-.00347,-.00107*
20,1,.006,-.00347,-.00107,-.00187,-.00213,0.0*
1,1,.006,-.00187,-.00213*
20,1,.006,-.00187,-.00213,0.0,-.0024,0.0*
1,1,.006,0.0,-.0024*
20,1,.006,0.0,-.0024,.00213,-.00187,0.0*
1,1,.006,.00213,-.00187*
20,1,.006,.00213,-.00187,.00373,-.00053,0.0*
1,1,.006,.00373,-.00053*
20,1,.006,.00373,-.00053,.00533,.00187,0.0*
1,1,.006,.00533,.00187*
%
%ADD15MACRO15*%
%AMMACRO17*
1,1,.006,0.0,.0785*
20,1,.006,0.0,.0785,-.067983,.03925,0.0*
1,1,.006,-.067983,.03925*
20,1,.006,-.067983,.03925,-.067983,-.03925,0.0*
1,1,.006,-.067983,-.03925*
20,1,.006,-.067983,-.03925,0.0,-.0785,0.0*
1,1,.006,0.0,-.0785*
20,1,.006,0.0,-.0785,.067983,-.03925,0.0*
1,1,.006,.067983,-.03925*
20,1,.006,.067983,-.03925,.067983,.03925,0.0*
1,1,.006,.067983,.03925*
20,1,.006,.067983,.03925,0.0,.0785,0.0*
1,1,.006,0.0,.0785*
1,1,.006,.0157,-.03925*
20,1,.006,.0157,-.03925,.0157,.03925,0.0*
1,1,.006,.0157,.03925*
20,1,.006,.0157,.03925,-.03271,-.01701,0.0*
1,1,.006,-.03271,-.01701*
20,1,.006,-.03271,-.01701,.03271,-.01701,0.0*
1,1,.006,.03271,-.01701*
%
%ADD17MACRO17*%
%AMMACRO13*
1,1,.006,0.0,.0455*
20,1,.006,0.0,.0455,.0455,-.0455,0.0*
1,1,.006,.0455,-.0455*
20,1,.006,.0455,-.0455,-.0455,-.0455,0.0*
1,1,.006,-.0455,-.0455*
20,1,.006,-.0455,-.0455,0.0,.0455,0.0*
1,1,.006,0.0,.0455*
1,1,.006,-.00152,-.02275*
20,1,.006,-.00152,-.02275,0.0,-.01289,0.0*
1,1,.006,0.0,-.01289*
20,1,.006,0.0,-.01289,.00228,-.00455,0.0*
1,1,.006,.00228,-.00455*
20,1,.006,.00228,-.00455,.00531,.00303,0.0*
1,1,.006,.00531,.00303*
20,1,.006,.00531,.00303,.0091,.01137,0.0*
1,1,.006,.0091,.01137*
20,1,.006,.0091,.01137,.01517,.02275,0.0*
1,1,.006,.01517,.02275*
20,1,.006,.01517,.02275,-.01517,.02275,0.0*
1,1,.006,-.01517,.02275*
%
%ADD13MACRO13*%
%ADD19C,.01*%
%ADD20C,.02*%
%ADD21C,.006*%
G75*
%LPD*%
G75*
G54D10*
X-38436Y23633D03*
X-36811Y1104775D03*
X-35919Y1969497D03*
X1072493Y21507D03*
X1075940Y1769358D03*
X1234250Y1573550D03*
G54D20*
G01X-87137Y-139897D02*
Y-107897D01*
G01X-75137Y-123897D02*
G02I-12000J0D01*
G01X-80287D02*
G02I-6850J0D01*
G01X-71137D02*
X-103137D01*
G01X-71137Y-139897D02*
Y-219897D01*
G01D02*
X1129963D01*
G01X-71137Y-175397D02*
X1129963D01*
G01X-71137Y-139897D02*
X1129963D01*
G01X342463D02*
Y-219897D01*
G01X479963Y-139897D02*
Y-219897D01*
G01X594963Y-139897D02*
Y-219897D01*
G01X762463Y-139897D02*
Y-219897D01*
G01X932463Y-139897D02*
Y-219897D01*
G01X1129963Y-139897D02*
Y-219897D01*
G01X1157963Y-123897D02*
G02I-12000J0D01*
G01X1152813D02*
G02I-6850J0D01*
G01X1161963D02*
X1129963D01*
G01X1145963Y-139897D02*
Y-107897D01*
G54D11*
X17600Y5604D03*
X10000Y16500D03*
X11999Y53550D03*
X11499Y34050D03*
X11999Y69050D03*
Y88550D03*
X11499Y106050D03*
X11999Y124550D03*
X11499Y142050D03*
X11999Y177050D03*
Y161550D03*
Y196550D03*
X11499Y214050D03*
X9499Y229050D03*
X8999Y246550D03*
X9499Y281550D03*
Y266050D03*
Y301050D03*
X15499Y328050D03*
X8999Y318550D03*
X15499Y342550D03*
Y360050D03*
X14799Y751450D03*
X8599Y751650D03*
X17299Y773950D03*
X10999Y774050D03*
X8999Y889550D03*
X8499Y907050D03*
X8999Y942050D03*
Y926550D03*
Y961550D03*
X8499Y979050D03*
X8999Y988550D03*
Y1025550D03*
X8499Y1006050D03*
X8999Y1041050D03*
Y1060550D03*
X8499Y1089050D03*
Y1078050D03*
X7999Y1106550D03*
X8499Y1126050D03*
Y1141550D03*
Y1161050D03*
X7999Y1192550D03*
Y1178550D03*
X7499Y1210050D03*
X7999Y1229550D03*
Y1245050D03*
Y1264550D03*
X7499Y1282050D03*
X8299Y1320050D03*
X8799Y1302550D03*
X18099Y1343550D03*
X9399Y1347350D03*
X15299Y1723450D03*
X15399Y1708350D03*
X7099Y1717750D03*
X7199Y1731450D03*
X14899Y1736250D03*
X15299Y1753250D03*
X6099Y1753750D03*
X11299Y1850050D03*
X9099Y1881550D03*
X8499Y1979550D03*
X11500Y1987000D03*
X36000Y5604D03*
X23499Y27050D03*
X40999Y27550D03*
X27799Y38450D03*
X40999Y42050D03*
X25799Y64050D03*
X28399Y94950D03*
X34999Y108550D03*
X41399Y134150D03*
X27999Y131050D03*
Y145550D03*
Y163050D03*
X23999Y243550D03*
Y229050D03*
Y261050D03*
X39999Y327550D03*
Y342050D03*
Y359550D03*
Y576550D03*
X36999Y725050D03*
Y719550D03*
X37499Y714050D03*
X41499Y719550D03*
X26399Y750850D03*
X36499Y740050D03*
Y732550D03*
X39899Y754850D03*
X39399Y768750D03*
X27199Y764950D03*
X28599Y775450D03*
X26799Y874550D03*
X26099Y891650D03*
X25699Y916150D03*
X25099Y942150D03*
X23899Y957950D03*
X24799Y992250D03*
X33899Y1005950D03*
X21499Y1073250D03*
X21399Y1090850D03*
X21299Y1300250D03*
X21799Y1282750D03*
X31499Y1849750D03*
X39399Y1864350D03*
X23999Y1857950D03*
X27199Y1874350D03*
X34799Y1890050D03*
X26500Y1987000D03*
X55700Y5900D03*
X50999Y21150D03*
Y47750D03*
X59499Y90550D03*
Y76050D03*
Y108050D03*
X52499Y130550D03*
Y145050D03*
Y162550D03*
X41699Y183250D03*
X48499Y243050D03*
Y228550D03*
Y260550D03*
X42999Y275650D03*
X51099Y300050D03*
X52199Y342350D03*
X42299Y564150D03*
X62055Y561550D03*
X49555Y563550D03*
X61099Y603236D03*
X52333Y641295D03*
X43499Y657550D03*
X47800Y692800D03*
X53210Y701486D03*
X50999Y720050D03*
X46499Y719550D03*
X51499Y724550D03*
X46499D03*
X41999D03*
X46499Y730550D03*
X41999Y735050D03*
Y731050D03*
X46499Y735050D03*
X41999Y739550D03*
X46499Y739050D03*
X51999Y767050D03*
X47999Y767550D03*
X52499Y771550D03*
X47999D03*
X53999Y791000D03*
X52999Y1871550D03*
X57499Y1871050D03*
X45699Y1875550D03*
X47499Y1915050D03*
Y1930550D03*
X62499Y1939550D03*
X58999Y1958050D03*
X61500Y1987500D03*
X44500Y1987000D03*
X55999Y1982550D03*
X73900Y6200D03*
X65499Y27050D03*
Y41550D03*
Y59050D03*
X77165Y110799D03*
X71015Y123666D03*
X78165Y137116D03*
X75299Y261750D03*
X76099Y414250D03*
X75300Y454100D03*
X67300Y450200D03*
X68899Y445450D03*
X66099Y500950D03*
X77165Y514650D03*
X70800Y540300D03*
X75999Y556640D03*
X72599Y578236D03*
X79299Y794150D03*
X67999Y790400D03*
X76399Y820450D03*
X70100Y818900D03*
X77499Y921550D03*
X77002Y952079D03*
X76711Y948089D03*
X77499Y962152D03*
X72799Y982950D03*
X65799Y994050D03*
X67000Y1011500D03*
X77165Y1327335D03*
X77166Y1353400D03*
X76499Y1507050D03*
Y1498050D03*
Y1512050D03*
Y1503050D03*
X76999Y1528050D03*
Y1519050D03*
X81499Y1589050D03*
X83499Y1594050D03*
X78999Y1593550D03*
X74999D03*
X74499Y1602050D03*
Y1598050D03*
X83499D03*
Y1602050D03*
X78999Y1598050D03*
Y1602050D03*
X83599Y1744750D03*
X77165Y1759550D03*
X78529Y1788113D03*
X78999Y1891550D03*
X82999D03*
Y1887550D03*
X78999D03*
X62999Y1914550D03*
X78999Y1896050D03*
X78433Y1900010D03*
X78999Y1904050D03*
X83499Y1896050D03*
X83433Y1904010D03*
X62999Y1926050D03*
X81499Y1915550D03*
X82499Y1957050D03*
X73499D03*
X66499D03*
X73499Y1945550D03*
X79500Y1987500D03*
X65499Y1982550D03*
X73499D03*
X82999D03*
X90900Y5800D03*
X90899Y14850D03*
X96999Y49550D03*
X92999Y52050D03*
X97800Y36000D03*
X96900Y40400D03*
X93000Y44900D03*
X92900Y39700D03*
X95814Y136065D03*
X96184Y151065D03*
Y166065D03*
X97999Y199050D03*
X92899Y231450D03*
X86899Y242750D03*
X93199Y279650D03*
X84899Y289250D03*
X90899Y309550D03*
X94199Y325550D03*
X93499Y337450D03*
X89899Y368350D03*
X95499Y355450D03*
X89999Y396450D03*
X87599Y403950D03*
X95399Y416350D03*
X89099Y426150D03*
X99399Y437450D03*
X93500Y445300D03*
X97699Y449850D03*
X93199D03*
X97999Y445550D03*
X94500Y456800D03*
X100500Y456700D03*
X98999Y488050D03*
X94499Y486550D03*
X93499Y477050D03*
X97699Y481550D03*
Y477050D03*
X93499Y481550D03*
X101500Y536500D03*
X93599Y581236D03*
X93100Y571640D03*
X92599Y606236D03*
X98001Y856950D03*
X97800Y851800D03*
X93808Y852063D03*
X94001Y856895D03*
X97499Y862050D03*
X93299D03*
X93499Y897152D03*
X93900Y882400D03*
X97900D03*
X97700Y887400D03*
X93690Y887139D03*
X97499Y892550D03*
X93499Y892050D03*
X93000Y907165D03*
X83988Y934028D03*
X86700Y982100D03*
X100999Y1101050D03*
X104999D03*
X100999Y1096550D03*
X102999Y1188050D03*
X104999Y1231050D03*
X100999Y1231032D03*
X103499Y1305050D03*
X93316Y1351000D03*
X96000Y1369000D03*
X96100Y1384650D03*
X97300Y1564100D03*
X92499Y1589050D03*
X86999D03*
X90999Y1628550D03*
Y1624550D03*
X91121Y1632549D03*
X86299Y1632550D03*
X85999Y1628550D03*
Y1624550D03*
X84099Y1737150D03*
X93499Y1759550D03*
X94336Y1773113D03*
X104417Y1791480D03*
X97999Y1815050D03*
X104500Y1813400D03*
X83999Y1900050D03*
Y1945050D03*
X98433Y1940510D03*
X98999Y1944550D03*
X102433Y1940555D03*
X103433Y1944510D03*
X92499Y1959050D03*
X101699Y1983850D03*
X98000Y1987500D03*
X91499Y1983050D03*
X107000Y6000D03*
X116400Y56000D03*
X114800Y68500D03*
X123499Y149050D03*
Y140050D03*
X117500Y162300D03*
X124300Y167800D03*
X109499Y410250D03*
X124899Y409050D03*
X126099Y396150D03*
X111299Y425850D03*
X122499Y427900D03*
X108599Y557236D03*
X108900Y587600D03*
X112200Y762200D03*
X112000Y773000D03*
X111299Y821050D03*
X112999Y901150D03*
X106500Y943000D03*
X105300Y960300D03*
X105006Y1096866D03*
X110999Y1130550D03*
X115200Y1130300D03*
X110999Y1126050D03*
Y1122050D03*
Y1118050D03*
X114999Y1126050D03*
Y1122050D03*
Y1118050D03*
X106999Y1114960D03*
X120999Y1188050D03*
X111999D03*
X121657Y1224604D03*
X120999Y1228550D03*
X120499Y1264550D03*
X123938Y1267623D03*
X117149Y1267550D03*
X123500Y1360300D03*
X122600Y1565000D03*
X124999Y1616050D03*
Y1620050D03*
Y1629050D03*
Y1633050D03*
X119999Y1629050D03*
X120100Y1633100D03*
X122499Y1668550D03*
Y1672550D03*
X118999Y1670550D03*
X105749Y1712749D03*
X117499Y1745050D03*
X123499Y1747050D03*
X120299Y1796150D03*
X111499Y1877550D03*
Y1882550D03*
X122999Y1883050D03*
X115999Y1882550D03*
X116499Y1877550D03*
X122999Y1889050D03*
X124433Y1908510D03*
X124999Y1912550D03*
X119999Y1978550D03*
X119499Y1972550D03*
X108499Y1981750D03*
X115000Y1987000D03*
X129100Y55900D03*
X127499Y65050D03*
X141999Y65550D03*
X129999Y78050D03*
X127999Y99550D03*
X133999Y149050D03*
X142999Y141050D03*
X132999Y141550D03*
X144499Y149050D03*
X131799Y201950D03*
X142688Y218861D03*
X143110Y203861D03*
X133000Y240500D03*
X135399Y277050D03*
X130799Y300250D03*
X130099Y326150D03*
X134699Y356050D03*
X139399Y372350D03*
X127999Y425050D03*
Y421050D03*
Y429550D03*
X133499Y445050D03*
X128999Y445550D03*
X130000Y452000D03*
X135999Y472550D03*
X135140Y478930D03*
X139200Y484300D03*
X134499Y488050D03*
X145649Y509550D03*
X136349Y509050D03*
X140499Y499050D03*
X136299D03*
X147300Y526700D03*
X140000Y587700D03*
X140499Y600550D03*
X143999Y605550D03*
X140499Y626050D03*
X131099Y700450D03*
X139099Y707150D03*
X141234Y1029885D03*
X140864Y1044885D03*
X137900Y1103400D03*
X139100Y1097100D03*
X134500Y1108100D03*
X143200Y1116300D03*
X133200Y1132100D03*
X126400Y1138100D03*
X145900Y1163200D03*
X144399Y1171150D03*
X141499Y1185550D03*
X128400Y1188600D03*
X143899Y1196750D03*
X142499Y1205550D03*
X130999Y1198050D03*
X144149Y1230113D03*
Y1226113D03*
Y1222113D03*
X126499Y1264550D03*
X145999Y1353050D03*
X143199Y1412050D03*
X140799Y1435460D03*
X129100Y1564700D03*
X127200Y1569800D03*
X126562Y1670613D03*
X130499Y1730050D03*
X128000Y1735000D03*
X144499Y1729550D03*
X139500Y1730500D03*
X133000Y1734500D03*
X144499Y1745550D03*
X137999Y1747723D03*
X129999Y1747050D03*
X126599Y1789650D03*
X142144Y1801644D03*
X143490Y1855972D03*
X127499Y1889050D03*
X126999Y1882550D03*
X142499Y1905972D03*
X141499Y1895972D03*
X129999Y1908550D03*
X129433Y1912510D03*
X127499Y1978550D03*
X133499D03*
X132999Y1972550D03*
X126999D03*
X146899Y1961750D03*
X146000Y1987500D03*
X128500D03*
X157299Y5150D03*
X167499Y43550D03*
X156499Y66050D03*
X166999Y88050D03*
X166499Y83550D03*
Y79050D03*
X158499D03*
Y84050D03*
Y88550D03*
Y93550D03*
X166999Y92550D03*
X165499Y106050D03*
X166999Y97050D03*
X152999Y141050D03*
X167499Y149550D03*
X163499Y140050D03*
X160999Y149550D03*
X155999Y181050D03*
X166800Y240800D03*
X158999Y259800D03*
X152808Y246341D03*
X157740Y273924D03*
X167299Y369350D03*
X150699Y411050D03*
X152499Y395950D03*
X149700Y471600D03*
X154100Y476500D03*
X164600Y476700D03*
X153499Y502550D03*
X148999D03*
X147590Y521500D03*
X154099Y529236D03*
X162500Y623400D03*
X152400Y643300D03*
X152124Y651868D03*
X159054Y665400D03*
X161999Y768050D03*
X152499Y810550D03*
Y816050D03*
Y820550D03*
Y825050D03*
X161999Y843550D03*
Y848050D03*
X156499Y846050D03*
X156999Y850050D03*
X156499Y870550D03*
Y876050D03*
X163999Y863050D03*
X159999D03*
X155999Y859050D03*
Y863050D03*
X158114Y883290D03*
X156499Y886950D03*
X159459Y896616D03*
X163499Y896550D03*
X155499Y891050D03*
Y896050D03*
X157499Y904550D03*
Y909050D03*
X151999Y936550D03*
X152499Y931550D03*
X153299Y943750D03*
X159186Y946117D03*
X156499Y985950D03*
X149499Y997650D03*
X162499Y1023550D03*
X158300Y1015000D03*
X163499Y1035050D03*
X159499Y1044579D03*
X151300Y1049300D03*
X165600Y1057428D03*
X168099Y1083550D03*
X164999Y1075550D03*
X159055Y1070400D03*
X167999Y1092850D03*
X167499Y1118550D03*
X167999Y1130550D03*
X163499Y1171650D03*
X151699Y1158550D03*
X151499Y1173050D03*
X150999Y1181150D03*
X148499Y1222113D03*
Y1226113D03*
X148486Y1230113D03*
X167499Y1389050D03*
X156999Y1397750D03*
X166799Y1409350D03*
X157915Y1420460D03*
X163499Y1433350D03*
X165499Y1453550D03*
X166799Y1487450D03*
X159054Y1476200D03*
X167499Y1714113D03*
X162499D03*
X165499Y1730613D03*
X167999Y1726613D03*
X163499D03*
X157500Y1797400D03*
X158000Y1825400D03*
X157999Y1840972D03*
X167200Y1868000D03*
X159054Y1855050D03*
X163599Y1892050D03*
X168299Y1879850D03*
X159054Y1881800D03*
X159173Y1935972D03*
X148499Y1977250D03*
X163500Y1987500D03*
X189499Y4550D03*
Y39150D03*
X183499Y45550D03*
X168499Y65550D03*
X169999Y103050D03*
X176499Y140050D03*
X177899Y199250D03*
X185999Y250550D03*
X181299Y267350D03*
X187199Y359050D03*
X181599Y396250D03*
X168999Y413050D03*
X188499Y413550D03*
X179999Y442550D03*
X179649Y438550D03*
X183999D03*
Y442550D03*
Y447050D03*
X179999D03*
X171300Y476700D03*
X187499Y531613D03*
Y536113D03*
X188999Y541113D03*
Y549613D03*
Y545613D03*
X181999Y624050D03*
Y609550D03*
Y641550D03*
X182599Y688350D03*
X171999Y672450D03*
X170799Y689150D03*
X178899Y765250D03*
X172599Y774250D03*
X168499Y846713D03*
X173899Y846550D03*
X172099Y877450D03*
X169299Y956350D03*
X171499Y998650D03*
X169299Y1067150D03*
X171599Y1139950D03*
X180400Y1202800D03*
X181700Y1219900D03*
X179800Y1244100D03*
X179500Y1262000D03*
X175823Y1297070D03*
X179999Y1301550D03*
Y1292550D03*
X175499D03*
X179999Y1296613D03*
X175499Y1302113D03*
X179999Y1306050D03*
X175499Y1306113D03*
X178200Y1393400D03*
X180599Y1424050D03*
X180000Y1439500D03*
X176599Y1447450D03*
X172299Y1465850D03*
X181500Y1479000D03*
X176299Y1500150D03*
X180299Y1626550D03*
X180000Y1619600D03*
X180299Y1634550D03*
X179733Y1630590D03*
X181900Y1675300D03*
X180701Y1716050D03*
X179701Y1724550D03*
X172499Y1714050D03*
X180000Y1731000D03*
X170499Y1731050D03*
X172499Y1726613D03*
X185999Y1746050D03*
X182299Y1801350D03*
X173899Y1813250D03*
X177599Y1866750D03*
X168499Y1855550D03*
X181099Y1885850D03*
X168699Y1957150D03*
X183999Y1968150D03*
X188199Y1978250D03*
X183000Y1987500D03*
X206999Y5050D03*
X197999Y39900D03*
X193999D03*
X208499Y45650D03*
X199999Y46050D03*
X194499Y44050D03*
X191999Y68050D03*
X192499Y57550D03*
X206899Y171650D03*
X190199Y178650D03*
X191999Y221550D03*
X203499Y250550D03*
X201199Y266750D03*
X209199Y365050D03*
X209499Y412550D03*
X209999Y426150D03*
X194999Y490050D03*
X190499Y487550D03*
X191199Y491550D03*
X205300Y508100D03*
X190499Y507513D03*
X193499Y541113D03*
Y549613D03*
X193999Y545550D03*
X206499Y623550D03*
Y609050D03*
X207300Y639400D03*
X199199Y659150D03*
X190399Y689050D03*
X209500Y759000D03*
X208799Y766750D03*
X190699Y778350D03*
X197099Y795050D03*
X208299Y805350D03*
X202900Y811900D03*
X198199Y805950D03*
X204496Y846111D03*
X204649Y838050D03*
X208999D03*
X209000Y846113D03*
X204649Y842113D03*
X208986D03*
X198499Y884113D03*
X204699Y929450D03*
X206699Y953050D03*
X203999Y943350D03*
X205999Y978250D03*
X206299Y990250D03*
X207299Y1008150D03*
X202100Y1028100D03*
X199499Y1093850D03*
X209900Y1093600D03*
X208199Y1145850D03*
X210199Y1173450D03*
X204199Y1163850D03*
X201600Y1205900D03*
X196499Y1215550D03*
Y1196550D03*
X196399Y1236650D03*
X196499Y1224550D03*
X195499Y1251050D03*
X202199Y1276850D03*
X195499Y1279050D03*
Y1270050D03*
X202899Y1291450D03*
X207699Y1337950D03*
X195500Y1352500D03*
X208049Y1385550D03*
X203199Y1393250D03*
X204699Y1418350D03*
X201000Y1408500D03*
X194200Y1457900D03*
X204999Y1472650D03*
X208999Y1491250D03*
X202399Y1500750D03*
X195700Y1619100D03*
X195600Y1623700D03*
X209200Y1624000D03*
X200600Y1663600D03*
X199900Y1670600D03*
X193499Y1674050D03*
X197600Y1694900D03*
X204400Y1688200D03*
X209901Y1691850D03*
X201801Y1701450D03*
X195001Y1708150D03*
X205200Y1708000D03*
X195500Y1717000D03*
X195000Y1725500D03*
X206900Y1726700D03*
X199699Y1761450D03*
X205199Y1801950D03*
X209999Y1825050D03*
X192100Y1813500D03*
X204399Y1855450D03*
X206999Y1867550D03*
X207199Y1892850D03*
X191599Y1891550D03*
X199599Y1879850D03*
X205499Y1968650D03*
X190199Y1957650D03*
X199600Y1974900D03*
X209699Y1978750D03*
X199000Y1987500D03*
X226499Y5050D03*
X225499Y52550D03*
Y46550D03*
Y63550D03*
Y58050D03*
X229099Y161350D03*
X227999Y178050D03*
X227499Y192050D03*
X227999Y187050D03*
Y182550D03*
X210999Y221550D03*
X217999Y250550D03*
X223799Y365350D03*
X217599Y396450D03*
X218499Y474850D03*
X224299Y494650D03*
X220499Y560050D03*
Y545550D03*
Y577550D03*
X224999Y613450D03*
X219999Y632550D03*
Y647050D03*
X226399Y677550D03*
X212999Y677350D03*
X218800Y668700D03*
X224099Y770250D03*
X214799Y774750D03*
X227199Y795050D03*
X217300Y816800D03*
X215999Y887550D03*
X220499D03*
X215499Y883550D03*
X219499Y939613D03*
X214999D03*
X219499Y926613D03*
X214999D03*
X225299Y957650D03*
X213999Y958650D03*
X219499Y948613D03*
Y943813D03*
X214999Y944113D03*
Y948613D03*
X217499Y981050D03*
X216999Y967550D03*
X217499Y998550D03*
X217999Y1012050D03*
X215999Y1039550D03*
X216499Y1053050D03*
X214499Y1154250D03*
X223099Y1182750D03*
X212499Y1184550D03*
Y1212550D03*
X221599Y1237250D03*
X220999Y1224350D03*
X222299Y1251850D03*
X229899Y1250550D03*
X211499Y1258050D03*
Y1239050D03*
X216300Y1274800D03*
X211499Y1267050D03*
X219099Y1325950D03*
X226599Y1340250D03*
X213199Y1350050D03*
X227399Y1363050D03*
X217499Y1387450D03*
X230599Y1400250D03*
X217999Y1408850D03*
X227999Y1421550D03*
X226300Y1447800D03*
X230899Y1437350D03*
X212400Y1433700D03*
X213399Y1500300D03*
X212899Y1535550D03*
X230999D03*
X211999Y1568550D03*
X231499Y1575050D03*
X224499D03*
X217999Y1574550D03*
X211999D03*
X218000Y1614300D03*
X228999Y1637550D03*
X211999Y1653550D03*
X230600Y1670500D03*
X213000Y1672500D03*
X216601Y1684350D03*
X226800Y1684200D03*
X220100Y1691700D03*
X212000Y1701300D03*
X222700Y1710100D03*
X222499Y1743850D03*
X221499Y1760950D03*
X220799Y1791550D03*
X215299Y1813950D03*
X224800Y1867000D03*
X228999Y1856050D03*
X212399Y1885850D03*
X226999Y1941050D03*
X227499Y1971050D03*
X221300Y1971200D03*
X225199Y1978750D03*
X216999Y1987550D03*
X241999Y5050D03*
X247499Y37550D03*
X246999Y46550D03*
Y56050D03*
X247499Y65050D03*
X244499Y136550D03*
Y122050D03*
X244900Y149100D03*
X231999Y178050D03*
Y192050D03*
Y187050D03*
Y182550D03*
X232400Y220700D03*
X249800Y248800D03*
X235399Y263350D03*
X237699Y426050D03*
X232999Y414550D03*
X252499Y415050D03*
X251499Y446050D03*
X231999Y445550D03*
X251999Y462050D03*
X232499Y461550D03*
X244199Y483350D03*
X242099Y511750D03*
X244999Y559550D03*
Y545050D03*
Y577050D03*
X244499Y632050D03*
X246500Y663300D03*
X245000Y647000D03*
X234200Y668300D03*
X245599Y773450D03*
X234299Y773750D03*
X247099Y795050D03*
X233799Y806350D03*
X245399Y823550D03*
X244099Y857450D03*
X252399Y838250D03*
X245199Y878050D03*
X232399Y886550D03*
X252899Y886350D03*
X245399Y907450D03*
X243899Y923650D03*
X242199Y938750D03*
X252499Y948850D03*
X244199Y973250D03*
X232299Y981950D03*
X233499Y966050D03*
X245899Y995250D03*
X233999Y997050D03*
Y1012550D03*
X232499Y1038050D03*
X249499Y1104150D03*
X232599Y1195750D03*
X251999Y1184550D03*
X242199Y1210050D03*
X242599Y1198350D03*
X247899Y1208650D03*
X234299Y1232650D03*
X250900Y1248500D03*
X242900Y1263000D03*
X232799Y1276150D03*
X241399Y1303250D03*
X239099Y1314150D03*
X252399Y1326350D03*
X245999Y1339050D03*
Y1358050D03*
X234300Y1375700D03*
X246499Y1370050D03*
X249800Y1388400D03*
X244999Y1412550D03*
X245499Y1424550D03*
X238899Y1453750D03*
X248000Y1482000D03*
X250199Y1473550D03*
X247500Y1499000D03*
X236999Y1535550D03*
X238300Y1575100D03*
X246200Y1617600D03*
X239400Y1624300D03*
X242999Y1658050D03*
X237400Y1663800D03*
X235499Y1697050D03*
X249199Y1743150D03*
X237999Y1730550D03*
X244999Y1755050D03*
X252199Y1793050D03*
X238699Y1801850D03*
X241199Y1867150D03*
X244700Y1878700D03*
X241255Y1896055D03*
X238999Y1970550D03*
X232999Y1971050D03*
X240900Y1979000D03*
X236500Y1987500D03*
X261499Y4550D03*
X253999Y48050D03*
X264999Y55350D03*
X261299Y75950D03*
X258699Y104550D03*
X265299Y96250D03*
X262299Y164050D03*
X262699Y208550D03*
X271999Y216050D03*
X265999Y245050D03*
X267498Y305114D03*
Y300114D03*
Y295114D03*
Y310114D03*
X258999Y396650D03*
X266699Y425050D03*
X269999Y415050D03*
X272499Y445050D03*
X266199Y472350D03*
X272999Y461050D03*
X257499Y498050D03*
Y512550D03*
Y530050D03*
X256499Y577050D03*
Y591550D03*
Y609050D03*
X269499Y616550D03*
X257199Y640050D03*
X269499Y631050D03*
Y648550D03*
X268499Y701550D03*
Y706550D03*
Y716550D03*
Y711550D03*
X268099Y795450D03*
X254699Y807650D03*
X264499Y829050D03*
X264999Y842550D03*
Y858450D03*
X265799Y901850D03*
X256199Y916250D03*
X254899Y929250D03*
X253499Y938050D03*
X269599Y923950D03*
X267199Y935350D03*
X264799Y946850D03*
X263299Y959350D03*
X272999Y981050D03*
Y965550D03*
X256499Y967050D03*
X262499Y995850D03*
X254499Y984550D03*
X258999Y1011550D03*
X269999Y1037050D03*
X253499Y1038550D03*
X269999Y1052550D03*
X253999Y1052050D03*
X272999Y1102850D03*
X262499Y1129150D03*
X260349Y1139200D03*
X272499Y1153050D03*
X268499D03*
X263999D03*
X259999Y1152992D03*
X271999Y1161550D03*
X267999D03*
X263499D03*
X259499D03*
X272999Y1214150D03*
X261199Y1227950D03*
X264800Y1261300D03*
X254899Y1289950D03*
X264799Y1313850D03*
X265299Y1339650D03*
X263699Y1359550D03*
X265499Y1376950D03*
X258999Y1396950D03*
X270599Y1408550D03*
X259299Y1438750D03*
X268499Y1453550D03*
X260999Y1503550D03*
X266999Y1512550D03*
X267349Y1518150D03*
Y1522550D03*
Y1527172D03*
X265700Y1635100D03*
X258700Y1645100D03*
X270999Y1660550D03*
X253999Y1676550D03*
X273499Y1694050D03*
X255699Y1722550D03*
X256499Y1710050D03*
X263499Y1734550D03*
X270599Y1748950D03*
X259499Y1760650D03*
X270599Y1801450D03*
X253899Y1813250D03*
X261499Y1825050D03*
X255999Y1855950D03*
X270299Y1867250D03*
X266999Y1915550D03*
Y1920050D03*
Y1924550D03*
Y1929050D03*
Y1933550D03*
X254500Y1987500D03*
X272000D03*
X278999Y5050D03*
X292999Y4550D03*
X294100Y28000D03*
X289499Y39050D03*
X286603Y34928D03*
X289999Y72550D03*
X290999Y67550D03*
X288499Y76550D03*
X289499Y80550D03*
X283599Y106250D03*
X274700Y131500D03*
X280999Y120050D03*
Y152050D03*
X290999Y216050D03*
X283499Y245050D03*
X279998Y304114D03*
Y299614D03*
Y295114D03*
Y308614D03*
X277799Y338599D03*
X293998Y361114D03*
Y356614D03*
Y352114D03*
X289998Y361114D03*
Y356614D03*
Y352114D03*
X276299Y376050D03*
X289399Y395750D03*
X284499Y415050D03*
X291599Y446150D03*
X286999Y462050D03*
X281999Y497550D03*
X292999Y483550D03*
X281999Y512050D03*
Y529550D03*
X277999Y545350D03*
X280999Y576550D03*
Y591050D03*
Y608550D03*
X293999Y616050D03*
Y630550D03*
Y648050D03*
X280999Y701550D03*
Y705550D03*
Y717550D03*
X280433Y713590D03*
X294999Y767050D03*
X290999D03*
X294999Y762550D03*
Y758050D03*
X290999Y762550D03*
Y758050D03*
X287799Y794850D03*
X275299Y806350D03*
X288899Y820550D03*
X280999Y827550D03*
X283599Y857450D03*
X293899Y843850D03*
X280999Y843050D03*
Y870050D03*
X281499Y883550D03*
X274299Y912950D03*
X287299Y901050D03*
X281099Y943550D03*
X278799Y956150D03*
X290099Y948650D03*
X289399Y963350D03*
X277599Y975250D03*
X288099Y971250D03*
X285399Y982950D03*
X294699Y989550D03*
X287099Y1000150D03*
X274999Y996550D03*
X289699Y1021750D03*
X275099Y1024750D03*
X274999Y1012050D03*
X287099Y1035050D03*
X282999Y1099550D03*
X274900Y1115600D03*
X290699Y1122650D03*
X283499Y1113050D03*
X276299Y1134550D03*
X283299Y1144850D03*
X291399Y1174150D03*
X279799Y1191750D03*
X286599Y1203750D03*
X283799Y1249250D03*
X274299Y1276450D03*
X281099Y1302850D03*
X286799Y1326450D03*
X286499Y1364050D03*
Y1345050D03*
X278799Y1386250D03*
X285499Y1399550D03*
X278000Y1422000D03*
X285499Y1418550D03*
Y1427550D03*
X286600Y1449700D03*
X279499Y1510550D03*
X286700Y1516100D03*
X279499Y1515050D03*
X279075Y1525957D03*
X278567Y1529925D03*
X293998Y1573614D03*
Y1569114D03*
X289998Y1573614D03*
Y1569114D03*
X293998Y1578114D03*
X289998D03*
X278499Y1621550D03*
X289000Y1641800D03*
X284300Y1676900D03*
X291099Y1707450D03*
X280499Y1718550D03*
X285499Y1742550D03*
X290699Y1760750D03*
X286599Y1791850D03*
X284299Y1811150D03*
X295299Y1870250D03*
X283999Y1856050D03*
X293999Y1933050D03*
X281999Y1918550D03*
Y1923550D03*
Y1928550D03*
X293999Y1971050D03*
Y1966550D03*
Y1962050D03*
X289499Y1961550D03*
Y1966550D03*
Y1971050D03*
X291499Y1987550D03*
X310499Y5050D03*
X304500Y44500D03*
X303300Y39500D03*
X308700Y39800D03*
X308800Y46400D03*
X306999Y55450D03*
X311299D03*
X315799Y55350D03*
X308499Y72550D03*
X303999Y74050D03*
X307999Y78550D03*
X306100Y126500D03*
X307199Y205550D03*
X310499Y216550D03*
X297999Y245050D03*
X313199Y270350D03*
X313000Y313900D03*
X305998Y352114D03*
X299899Y376650D03*
X310999Y396250D03*
X300899Y431850D03*
X303999Y415550D03*
X306100Y462000D03*
X312499Y484050D03*
X298599Y501250D03*
X309399Y513450D03*
X297599Y519350D03*
X307499Y555550D03*
Y541050D03*
X297499Y551050D03*
X296199Y568550D03*
X307499Y573050D03*
X302899Y607950D03*
X307499Y661550D03*
Y647050D03*
X297699Y681850D03*
X307499Y679050D03*
X308899Y705150D03*
X298399Y703450D03*
X296399Y716950D03*
X306999Y758050D03*
X314499Y754550D03*
X307999Y803150D03*
X307899Y794550D03*
X300199Y835250D03*
X304899Y856150D03*
X313499Y847850D03*
X315199Y869450D03*
X297499Y868550D03*
X302499Y899050D03*
X297499Y884050D03*
X302199Y914650D03*
X315199Y925950D03*
X310699Y943550D03*
X299399Y965950D03*
X298099Y977250D03*
X307999Y970650D03*
X306699Y981250D03*
X304399Y997550D03*
X298399Y1008150D03*
X306399Y1020750D03*
X303699Y1038050D03*
X299999Y1052350D03*
X304699Y1057050D03*
X312299Y1093550D03*
X299499Y1098050D03*
Y1113550D03*
X316499Y1124550D03*
X307999Y1142050D03*
X304499Y1156650D03*
X313499Y1170150D03*
X300699Y1185150D03*
X315408Y1202663D03*
X311999Y1213850D03*
X300699Y1227350D03*
X310299Y1240050D03*
X304699Y1265850D03*
X312499Y1280350D03*
X295399Y1292950D03*
X300499Y1305350D03*
X311500Y1316300D03*
X297899Y1336150D03*
X298099Y1357250D03*
X311900Y1344900D03*
X301699Y1377950D03*
X312900Y1366900D03*
X301699Y1395750D03*
X313600Y1391300D03*
X303499Y1411250D03*
X312100Y1420700D03*
X300899Y1433350D03*
X313600Y1442700D03*
X304699Y1457550D03*
X312800Y1467400D03*
X296599Y1497150D03*
X312000Y1514600D03*
X305998Y1569114D03*
X307000Y1619600D03*
X302399Y1662950D03*
X299999Y1696050D03*
X303999Y1722050D03*
X297099Y1733850D03*
X303499Y1753550D03*
X303999Y1800850D03*
X315499Y1812250D03*
X298999Y1855950D03*
X313599Y1870250D03*
X308099Y1880550D03*
X313599Y1889250D03*
X314099Y1901250D03*
X305999Y1913050D03*
X306999Y1932550D03*
X302499D03*
X298499D03*
X302499Y1922050D03*
X296858Y1956228D03*
X305999Y1964050D03*
Y1969550D03*
X311500Y1987500D03*
X329999Y5050D03*
X332200Y94200D03*
X321799Y173950D03*
X317499Y192950D03*
X331499Y193250D03*
X325499Y249450D03*
X337499Y282550D03*
X316999Y312576D03*
X321748Y343299D03*
X328799Y372350D03*
X336099Y417550D03*
X322099Y426850D03*
X324999Y414550D03*
X328599Y442250D03*
X327900Y463200D03*
X333499Y483050D03*
X329999Y510450D03*
X321999Y533150D03*
X331999Y555050D03*
Y540550D03*
X321999Y550550D03*
X321299Y565250D03*
X320799Y582050D03*
X331999Y572550D03*
X328599Y602450D03*
X328499Y635650D03*
X317999Y627850D03*
X331999Y661050D03*
Y646550D03*
Y678550D03*
X324599Y696150D03*
X330799Y712450D03*
X318999Y814350D03*
X325599Y823950D03*
X330299Y871850D03*
X323799Y859850D03*
X321099Y899650D03*
X323099Y885050D03*
X322099Y913650D03*
X331099Y923650D03*
X328099Y937250D03*
X323499Y956950D03*
X329799Y970650D03*
X333099Y983450D03*
X320999Y997250D03*
X331299Y1017150D03*
X321299Y1012450D03*
Y1024750D03*
X331599Y1028750D03*
X329599Y1040750D03*
X318299Y1038750D03*
X329599Y1057050D03*
X319999Y1066950D03*
X317699Y1054650D03*
X329299Y1098550D03*
X326599Y1112350D03*
X332999Y1123050D03*
X323999Y1153250D03*
X332999Y1138550D03*
X317999Y1137550D03*
X329799Y1182750D03*
X328999Y1200550D03*
X326649Y1227850D03*
Y1218850D03*
X327999Y1255050D03*
X333349Y1270500D03*
Y1288900D03*
Y1307000D03*
Y1332800D03*
Y1363500D03*
Y1393100D03*
Y1429500D03*
Y1481900D03*
X332500Y1519700D03*
X337199Y1636350D03*
X320299Y1642950D03*
X316799Y1657450D03*
X335767Y1662735D03*
X318499Y1675550D03*
X334399Y1691650D03*
X329999Y1716950D03*
X320999Y1706050D03*
X321999Y1733050D03*
X326301Y1766030D03*
X321499Y1772550D03*
X327299Y1791850D03*
X322299Y1802150D03*
X334999Y1797050D03*
X337499Y1855950D03*
X316999D03*
X336799Y1869950D03*
X326399Y1876250D03*
X336799Y1888950D03*
X326899Y1907250D03*
X326399Y1895250D03*
X336799Y1897950D03*
X335799Y1916450D03*
X326799Y1977050D03*
X329999Y1987550D03*
X345499Y5050D03*
X356499Y113050D03*
X351999D03*
X347499D03*
X355999Y100550D03*
X350999D03*
X345999D03*
X354099Y175350D03*
X343399Y161350D03*
X343999Y190050D03*
X343799Y204550D03*
X355499Y219050D03*
X337999D03*
X355999Y242750D03*
X343499Y253550D03*
X347699Y269050D03*
X354999Y282550D03*
X347399Y301950D03*
X339399Y358050D03*
X357999Y359050D03*
X354099Y373050D03*
X338399Y395650D03*
X338899Y433850D03*
X354699Y426650D03*
X356399Y451750D03*
X351399Y470750D03*
X340799Y512050D03*
X358399Y498650D03*
X341399Y535850D03*
X357399Y521250D03*
Y530550D03*
X341399Y558950D03*
X357399Y543850D03*
X357999Y559450D03*
X340299Y586550D03*
X342199Y613050D03*
X342099Y646350D03*
X341899Y664950D03*
X342599Y678850D03*
X345399Y698950D03*
X357699Y707750D03*
X341399Y715050D03*
X355999Y752850D03*
X353999Y787750D03*
X347699Y773450D03*
X338099Y811650D03*
X338599Y821650D03*
Y840450D03*
X340099Y887350D03*
X338399Y901050D03*
X340099Y910350D03*
X340399Y931250D03*
X340099Y952850D03*
X339599Y1081550D03*
X344399Y1338150D03*
X343599Y1360050D03*
X344099Y1393750D03*
Y1421150D03*
Y1449550D03*
X351899Y1570850D03*
X344500Y1583600D03*
X350600Y1610900D03*
X349099Y1634550D03*
X351099Y1691150D03*
X352000Y1700400D03*
X343899Y1752650D03*
X357999Y1796050D03*
X355699Y1810750D03*
X351999Y1855450D03*
X348999Y1879050D03*
X349499Y1910050D03*
X348999Y1898050D03*
X347999Y1925550D03*
X348499Y1956550D03*
X347999Y1944550D03*
X347699Y1972250D03*
X345499Y1987550D03*
X364999Y4550D03*
X371999Y15550D03*
X376499D03*
X369999Y23550D03*
Y19050D03*
X376999Y65550D03*
Y70050D03*
X360999Y113050D03*
Y100550D03*
X363999Y136050D03*
Y121550D03*
Y153550D03*
X362999Y190050D03*
X369999Y219050D03*
X362499Y253550D03*
X369499Y282550D03*
X359399Y307250D03*
X368299Y386350D03*
X359399Y576050D03*
Y599650D03*
X360399Y615550D03*
X359699Y627550D03*
X358899Y657150D03*
X359399Y669450D03*
X359199Y690650D03*
X377499Y1182050D03*
Y1210050D03*
Y1201050D03*
X376499Y1236550D03*
Y1255550D03*
Y1264550D03*
X376599Y1293950D03*
X375599Y1323350D03*
X374499Y1347550D03*
Y1375550D03*
Y1366550D03*
X373499Y1402050D03*
Y1421050D03*
X376299Y1437650D03*
X373499Y1430050D03*
X373099Y1456550D03*
X374799Y1491250D03*
X374099Y1554550D03*
X376099Y1572850D03*
X375099Y1608250D03*
X377700Y1629000D03*
X374999Y1656750D03*
X377099Y1696350D03*
X359499Y1736850D03*
X376799Y1734050D03*
X376499Y1775550D03*
X369499Y1855950D03*
X359999Y1878550D03*
X369799Y1880050D03*
X359999Y1897550D03*
Y1906550D03*
X369999Y1901950D03*
X358999Y1925050D03*
X369199Y1919750D03*
X367299Y1956950D03*
X367999Y1940250D03*
X367299Y1972950D03*
X364999Y1987050D03*
X382499Y5050D03*
X395999Y5550D03*
X380999Y15550D03*
X382499Y20050D03*
X381499Y65550D03*
Y70050D03*
X389599Y90950D03*
X380599Y103550D03*
X381299Y136750D03*
X400499Y134050D03*
Y119550D03*
Y151550D03*
X389299Y161650D03*
X382499Y190550D03*
X387599Y220150D03*
X385999Y207250D03*
X381999Y254050D03*
X382999Y276650D03*
X386899Y299250D03*
X383299Y310250D03*
X386599Y348450D03*
X394899Y357750D03*
X380599Y381050D03*
X380099Y1709650D03*
X393499Y1759550D03*
X393999Y1784550D03*
X387899Y1802850D03*
X391499Y1855950D03*
X389499Y1885050D03*
Y1913050D03*
Y1904050D03*
X388499Y1932950D03*
Y1950550D03*
X385099Y1975950D03*
X399299Y1976750D03*
X388499Y1959550D03*
X382499Y1987550D03*
X413499Y6050D03*
X416999Y25050D03*
X417499Y46550D03*
X416999Y63550D03*
X417499Y79050D03*
Y93550D03*
Y108050D03*
Y125550D03*
X416999Y145050D03*
Y164050D03*
X417999Y185050D03*
X412999Y275550D03*
Y307550D03*
Y290050D03*
X422199Y363350D03*
X420199Y391350D03*
X415099Y422550D03*
X410799Y431150D03*
X419599Y458550D03*
X415999Y518550D03*
X420199Y638550D03*
X418799Y877050D03*
Y896050D03*
X409499Y1102550D03*
X419999Y1115550D03*
X415499Y1161550D03*
X416099Y1183550D03*
X415499Y1176050D03*
X419499Y1234050D03*
Y1219550D03*
X420099Y1241550D03*
X416699Y1342650D03*
X416199Y1367550D03*
X414799Y1532350D03*
X418299Y1561250D03*
X415999Y1603250D03*
X416199Y1625250D03*
X414799Y1653750D03*
X414399Y1678350D03*
X414499Y1707250D03*
X410757Y1772872D03*
X417799Y1790850D03*
X414499Y1810450D03*
X406999Y1855950D03*
X421399Y1888050D03*
X406499Y1893050D03*
Y1874050D03*
X421399Y1907050D03*
X406999Y1905050D03*
X420399Y1934550D03*
X421399Y1916050D03*
X405499Y1920550D03*
X420399Y1953550D03*
X405999Y1951550D03*
X405499Y1939550D03*
X420399Y1962550D03*
X420799Y1977250D03*
X420500Y1987000D03*
X403500D03*
X432999Y6050D03*
X436499Y31350D03*
Y50350D03*
X437499Y71350D03*
X441799Y102450D03*
Y121450D03*
X442799Y142450D03*
X430499Y217050D03*
X423799Y259750D03*
X437499Y275050D03*
Y307050D03*
Y289550D03*
X422499Y348150D03*
X438999Y381550D03*
X426599Y415350D03*
X443199Y440850D03*
X440099Y459250D03*
X431099Y479350D03*
X435499Y519050D03*
X430099Y551450D03*
X427999Y580050D03*
Y565550D03*
Y597550D03*
X427499Y624550D03*
X437299Y744650D03*
X435299Y763150D03*
X424999Y766550D03*
X435299Y777650D03*
X422999Y785050D03*
X434799Y814650D03*
X435299Y795150D03*
X422999Y799550D03*
X434799Y833650D03*
X422999Y817050D03*
X422499Y855550D03*
Y836550D03*
X442599Y905650D03*
Y924650D03*
X423299Y994050D03*
Y1013050D03*
X424299Y1034050D03*
X432599Y1064550D03*
X433599Y1085550D03*
X428999Y1102550D03*
X439499Y1115550D03*
X436999Y1128050D03*
X437599Y1150050D03*
X436999Y1142550D03*
X443199Y1224250D03*
Y1238750D03*
X424999Y1278550D03*
Y1259550D03*
X425499Y1290550D03*
X428499Y1325350D03*
X434499Y1360250D03*
X422299Y1394950D03*
X441499Y1399550D03*
X426799Y1416050D03*
X441499Y1414050D03*
X423299Y1430350D03*
X425799Y1447950D03*
X441499Y1431550D03*
X427099Y1469150D03*
X424299Y1541350D03*
X439599Y1552150D03*
X434500Y1579500D03*
X432499Y1617550D03*
X431999Y1605550D03*
X425499Y1635050D03*
X432400Y1680100D03*
X427499Y1662050D03*
X428600Y1691200D03*
X435300Y1715300D03*
X429499Y1748050D03*
X441499Y1758050D03*
X436799Y1772550D03*
X422999Y1778550D03*
X426499Y1855450D03*
X434299Y1876050D03*
Y1904050D03*
Y1895050D03*
X433299Y1922550D03*
Y1950550D03*
Y1941550D03*
X436299Y1977250D03*
X438999Y1987550D03*
X448499Y6050D03*
X445799Y165650D03*
Y184650D03*
X446799Y205650D03*
X449999Y217050D03*
X448999Y255550D03*
X444499Y283050D03*
X463999Y283550D03*
X443499Y354050D03*
X464499Y353050D03*
X458499Y382050D03*
X450300Y404200D03*
X453999Y417550D03*
X454999Y438550D03*
X454499Y472550D03*
Y458050D03*
Y490050D03*
X456499Y518050D03*
X453999Y509550D03*
X452499Y579550D03*
Y565050D03*
Y597050D03*
X463999Y659550D03*
X450399Y672750D03*
X444799Y687350D03*
X463999Y674050D03*
Y691550D03*
X451099Y711650D03*
X452099Y762450D03*
Y781450D03*
X453399Y807950D03*
Y826950D03*
X462999Y865050D03*
Y884050D03*
X464499Y896050D03*
X462499Y914550D03*
Y929050D03*
X443599Y945650D03*
X462499Y946550D03*
X461999Y966050D03*
Y985050D03*
X462499Y1043850D03*
Y1062850D03*
X463499Y1083850D03*
X463999Y1102050D03*
X444499Y1102550D03*
X454999Y1115550D03*
X453499Y1140550D03*
X454499Y1161550D03*
X443799Y1246250D03*
Y1274250D03*
Y1265250D03*
X448099Y1341250D03*
X444899Y1377950D03*
X464199Y1401450D03*
X459999Y1424050D03*
X456399Y1445950D03*
X459699Y1468050D03*
X445099Y1464250D03*
X444299Y1532650D03*
X461399Y1541650D03*
X452199Y1550650D03*
X449199Y1579050D03*
X443799Y1612250D03*
X460199Y1632850D03*
X449599Y1656950D03*
X448399Y1699450D03*
X447699Y1682850D03*
X458499Y1742050D03*
X463999Y1772050D03*
X445499Y1792550D03*
X448099Y1809450D03*
X443999Y1855950D03*
X460299Y1892350D03*
X446999Y1880050D03*
X460299Y1911350D03*
X446999Y1908050D03*
Y1899050D03*
X460299Y1920350D03*
X445999Y1926550D03*
X459299Y1938850D03*
X445999Y1954550D03*
Y1945550D03*
X459299Y1966850D03*
Y1957850D03*
X455799Y1976750D03*
X456500Y1987500D03*
X467999Y5550D03*
X485499Y6050D03*
X465799Y24750D03*
Y43750D03*
X466799Y64750D03*
X470399Y84550D03*
Y103550D03*
X471399Y124550D03*
X473099Y141050D03*
X483599Y179350D03*
X473099Y160050D03*
X474099Y181050D03*
X472999Y214550D03*
X469999Y254550D03*
X481499Y283550D03*
X466399Y304950D03*
X479299Y297250D03*
X483499Y353050D03*
X485000Y373200D03*
X484900Y394700D03*
X468799Y414250D03*
X472499Y458050D03*
X471499Y493950D03*
X485299Y534550D03*
X479999Y581050D03*
Y566550D03*
Y598550D03*
X472999Y736550D03*
X467699Y772750D03*
X468699Y788350D03*
X479599Y847550D03*
X475699Y880450D03*
X483499Y1064850D03*
X484499Y1085850D03*
X481499Y1102550D03*
X474499Y1115050D03*
X473099Y1144550D03*
X474099Y1165550D03*
X465499Y1265550D03*
Y1284550D03*
Y1293550D03*
X468999Y1323950D03*
X473999Y1342450D03*
X468699Y1362850D03*
X485599Y1367550D03*
X466699Y1378150D03*
X481499Y1402550D03*
Y1417050D03*
X482599Y1449950D03*
X478299Y1464850D03*
X466999Y1530650D03*
X474299Y1544750D03*
X472299Y1572050D03*
X484200Y1579900D03*
X465999Y1603450D03*
X472499Y1611550D03*
X484999Y1636550D03*
X472499Y1620550D03*
X483599Y1662550D03*
X467999Y1668050D03*
X485599Y1694850D03*
X467999Y1687050D03*
Y1696050D03*
X468499Y1712550D03*
X480999Y1756050D03*
X484999Y1779050D03*
X472699Y1792150D03*
X481299Y1811150D03*
X480499Y1855450D03*
X464999D03*
X476199Y1877450D03*
Y1905450D03*
Y1896450D03*
X475199Y1923950D03*
Y1951950D03*
Y1942950D03*
X473299Y1977250D03*
X476000Y1987000D03*
X498999Y6050D03*
X499999Y25550D03*
X500499Y47050D03*
X499999Y64050D03*
X500499Y79550D03*
Y94050D03*
Y108550D03*
Y126050D03*
X499999Y145550D03*
Y164550D03*
X504199Y193250D03*
X502899Y217150D03*
X488999Y254550D03*
X495999Y283550D03*
X502999Y353550D03*
X490999Y412550D03*
X503699Y419250D03*
X490999Y427050D03*
Y444550D03*
X498399Y470050D03*
X490499Y464050D03*
Y483050D03*
X491499Y504050D03*
X504499Y580550D03*
Y566050D03*
Y598050D03*
X488499Y659050D03*
Y673550D03*
Y691050D03*
X506599Y711650D03*
X487299Y716950D03*
X490299Y734550D03*
X489599Y752450D03*
X495999Y795050D03*
X493999Y813550D03*
Y828050D03*
Y845550D03*
X493499Y865050D03*
Y884050D03*
X485799Y920050D03*
Y901050D03*
X486799Y941050D03*
X493099Y996350D03*
X494099Y1017350D03*
X501499Y1102550D03*
X491999Y1115550D03*
X504399Y1132250D03*
X505399Y1153250D03*
X486499Y1210550D03*
Y1196050D03*
X506599Y1202350D03*
Y1216850D03*
X487099Y1218050D03*
X498299Y1323350D03*
X499199Y1350550D03*
X498899Y1386450D03*
Y1408350D03*
X500899Y1434350D03*
X505899Y1466250D03*
X488299Y1531050D03*
X499699Y1538950D03*
X502199Y1566250D03*
X487099Y1606250D03*
X501399Y1634550D03*
X502899Y1709650D03*
X496999Y1799550D03*
X499999Y1854950D03*
X505799Y1893050D03*
X492999Y1878050D03*
X505799Y1912050D03*
X493499Y1909050D03*
X492999Y1897050D03*
X505799Y1921050D03*
X491999Y1924550D03*
X504799Y1939550D03*
X492499Y1955550D03*
X491999Y1943550D03*
X504799Y1967550D03*
Y1958550D03*
X493799Y1977250D03*
X492500Y1987500D03*
X516499Y6550D03*
X522899Y45350D03*
Y64350D03*
X523899Y85350D03*
X520299Y122450D03*
Y141450D03*
X521299Y162450D03*
X508499Y255050D03*
X525999D03*
X515499Y284050D03*
X516899Y306950D03*
X520499Y353550D03*
X509999Y382550D03*
X518999Y416550D03*
X511299Y449150D03*
X519499Y471550D03*
Y489050D03*
X508699Y498950D03*
X518999Y508550D03*
X514499Y546050D03*
X509999Y640550D03*
Y655050D03*
Y672550D03*
X527499Y747150D03*
X525499Y772450D03*
X511199Y782050D03*
X512899Y823550D03*
X526499Y851150D03*
X512899Y842550D03*
X510899Y868150D03*
X522499Y876050D03*
X521999Y895550D03*
X506899Y919950D03*
Y900950D03*
X521999Y914550D03*
X516499Y957050D03*
X514499Y975550D03*
Y990050D03*
Y1007550D03*
X513999Y1046050D03*
Y1027050D03*
X518999Y1103050D03*
X511999Y1115550D03*
X527499Y1181550D03*
X527999Y1212550D03*
X527499Y1200550D03*
X507199Y1224350D03*
X525999Y1231050D03*
X507199Y1252350D03*
Y1243350D03*
X525999Y1245550D03*
X527499Y1278150D03*
X525999Y1263050D03*
X518499Y1346950D03*
X523499Y1360050D03*
X508599Y1370550D03*
X523499Y1379050D03*
X523999Y1391050D03*
X516999Y1418050D03*
Y1437050D03*
X517499Y1449050D03*
X518899Y1530150D03*
X510100Y1579800D03*
X508199Y1610450D03*
X518499Y1643950D03*
X509199Y1660550D03*
X507399Y1683350D03*
X522300Y1739200D03*
X508200Y1758200D03*
X515499Y1779050D03*
X526499Y1801150D03*
X514199Y1815750D03*
X517499Y1855450D03*
X519399Y1876750D03*
Y1904750D03*
Y1895750D03*
X518399Y1923250D03*
Y1951250D03*
Y1942250D03*
X509299Y1977250D03*
X511999Y1987550D03*
X535999Y6550D03*
X541499Y25050D03*
X541999Y46550D03*
X541499Y63550D03*
X541999Y79050D03*
Y93550D03*
Y108050D03*
Y125550D03*
X541499Y145050D03*
Y164050D03*
X528799Y199950D03*
X542499Y185050D03*
X533499Y217550D03*
X540499Y255050D03*
X536499Y283050D03*
X544799Y293950D03*
X540099Y306550D03*
X548100Y362200D03*
X530999Y381550D03*
X538799Y445050D03*
X539799Y466050D03*
X539299Y485550D03*
X535499Y545050D03*
X538999Y562050D03*
X534499Y640050D03*
Y654550D03*
Y672050D03*
X547999Y728550D03*
Y743050D03*
Y760550D03*
X547499Y780050D03*
X534499Y805950D03*
X547499Y799050D03*
X541399Y854450D03*
Y873450D03*
X539299Y935850D03*
X540299Y956850D03*
X540899Y981450D03*
Y1000450D03*
X541899Y1021450D03*
X534599Y1048550D03*
X535599Y1069550D03*
X538499Y1103050D03*
X548999Y1116050D03*
X529499D03*
X546499Y1180750D03*
Y1195250D03*
X547099Y1202750D03*
Y1230750D03*
Y1221750D03*
X548799Y1252850D03*
Y1267350D03*
X530499Y1297050D03*
X545099Y1355250D03*
X540399Y1382150D03*
X538799Y1409750D03*
X536799Y1436350D03*
X528499Y1460250D03*
X546099Y1467550D03*
X538999Y1528350D03*
X529799Y1555050D03*
X533800Y1575500D03*
X529499Y1616550D03*
X528999Y1604550D03*
X532499Y1635550D03*
X532599Y1655650D03*
X532499Y1669550D03*
Y1688550D03*
X532999Y1700550D03*
X538299Y1721050D03*
X532499Y1763050D03*
X539499Y1788150D03*
X544300Y1784638D03*
X531799Y1818450D03*
X538999Y1855950D03*
X547999Y1892350D03*
X533499Y1884050D03*
X547999Y1911350D03*
X533499Y1912050D03*
Y1903050D03*
X547999Y1920350D03*
X532499Y1930550D03*
X546999Y1938850D03*
X532499Y1949550D03*
X546999Y1966850D03*
Y1957850D03*
X546299Y1977250D03*
X528799Y1976750D03*
X532499Y1958550D03*
X531500Y1987500D03*
X551499Y6550D03*
X568099Y72550D03*
Y91550D03*
X569099Y112550D03*
X562799Y127750D03*
Y146750D03*
X563799Y167750D03*
X565999Y199950D03*
X568499Y217550D03*
X552999D03*
X557999Y322550D03*
Y326550D03*
X558099Y335050D03*
X557933Y331010D03*
X555999Y412550D03*
X556499Y467550D03*
Y485050D03*
X555999Y504550D03*
X558499Y562550D03*
Y616050D03*
X554304Y615840D03*
X554499Y624550D03*
X558699D03*
X554499Y620050D03*
X558709Y620245D03*
X565699Y710650D03*
X549999Y710050D03*
X562999Y898050D03*
X560999Y916550D03*
Y931050D03*
Y948550D03*
X560499Y968050D03*
Y987050D03*
X560999Y999050D03*
X558999Y1017550D03*
Y1032050D03*
X558499Y1069050D03*
X558999Y1049550D03*
X558499Y1088050D03*
X568499Y1101550D03*
X553999Y1103050D03*
X564499Y1116050D03*
X567999Y1187550D03*
Y1215550D03*
Y1206550D03*
X565999Y1234050D03*
Y1248550D03*
X566399Y1273850D03*
X549399Y1274850D03*
X561099Y1301050D03*
X549399Y1293850D03*
Y1302850D03*
X555699Y1322950D03*
X559099Y1343250D03*
X557499Y1424050D03*
Y1443050D03*
Y1452050D03*
X563499Y1486550D03*
Y1492050D03*
Y1497550D03*
Y1503550D03*
X567999Y1549950D03*
X552199Y1576650D03*
X552099Y1601950D03*
X569499Y1610550D03*
X553399Y1624550D03*
X569499Y1619550D03*
X554199Y1651950D03*
X555199Y1674750D03*
X555399Y1689350D03*
X555899Y1706750D03*
X556199Y1727050D03*
X560399Y1792550D03*
X555500Y1802700D03*
X554499Y1855950D03*
X562599Y1893450D03*
Y1874450D03*
Y1902450D03*
X561599Y1920950D03*
Y1948950D03*
Y1939950D03*
X570299Y1976250D03*
X568999Y1987050D03*
X553499D03*
X570999Y6050D03*
X588499Y6550D03*
X587999Y25050D03*
X588499Y46550D03*
X587999Y63550D03*
X588499Y125550D03*
X587999Y145050D03*
Y164050D03*
X588999Y185050D03*
X587999Y217050D03*
X572999Y255050D03*
Y269550D03*
Y287050D03*
X572499Y306550D03*
Y325550D03*
X573499Y346550D03*
X579899Y375750D03*
X577399Y420050D03*
X578399Y441050D03*
X577899Y460550D03*
X576099Y481850D03*
X577099Y502850D03*
X576599Y522350D03*
X579499Y561550D03*
X573499Y658550D03*
Y673050D03*
Y690550D03*
X586299Y711250D03*
X577999Y732050D03*
X575999Y750550D03*
Y765050D03*
Y782550D03*
X575499Y802050D03*
Y821050D03*
X576499Y842050D03*
X578299Y895650D03*
Y914650D03*
X583299Y961450D03*
X570899Y946850D03*
X583299Y980450D03*
X570899Y965850D03*
X571899Y986850D03*
X573499Y1036550D03*
Y1055550D03*
X574499Y1076550D03*
X588499Y1101550D03*
X578999Y1114550D03*
X582699Y1233250D03*
X583299Y1255250D03*
X582699Y1247750D03*
X583299Y1274250D03*
X579299Y1300750D03*
X583299Y1283250D03*
X581999Y1370150D03*
X580999Y1412750D03*
X575699Y1438950D03*
X582999Y1461250D03*
X590599Y1483450D03*
X582299Y1534150D03*
X588099Y1572050D03*
X573400Y1577600D03*
X588000Y1604000D03*
X590799Y1627850D03*
X580799Y1646150D03*
X572999Y1675550D03*
X590599Y1694450D03*
X572999Y1694550D03*
Y1703550D03*
X580299Y1722550D03*
X582599Y1740050D03*
X573999Y1855450D03*
X588899Y1882350D03*
X575999Y1888050D03*
X588899Y1910350D03*
Y1901350D03*
X575999Y1907050D03*
X587899Y1928850D03*
X576499Y1919050D03*
X574999Y1934550D03*
X587899Y1956850D03*
Y1947850D03*
X574999Y1953550D03*
X585799Y1976250D03*
X575499Y1965550D03*
X588499Y1986550D03*
X608499Y6550D03*
X603999Y35350D03*
Y54350D03*
X604999Y75350D03*
X603999Y133750D03*
Y152750D03*
X604999Y173750D03*
X605499Y217550D03*
X599299Y344650D03*
X600299Y365650D03*
X599799Y385150D03*
X607399Y380250D03*
X592999Y407550D03*
Y422050D03*
Y439550D03*
X592499Y459050D03*
Y478050D03*
X593499Y499050D03*
X606499Y584550D03*
X595999Y624050D03*
Y609550D03*
Y641550D03*
X605299Y661750D03*
X609499Y708050D03*
X597999Y690050D03*
X607499Y726550D03*
Y741050D03*
Y758550D03*
X606999Y778050D03*
Y797050D03*
X603499Y904050D03*
X601499Y922550D03*
Y937050D03*
Y954550D03*
X600999Y1002050D03*
X611399Y1026650D03*
X598999Y1020550D03*
X611399Y1045650D03*
X598999Y1035050D03*
X612399Y1066650D03*
X598999Y1052550D03*
X598499Y1072050D03*
X605999Y1102050D03*
X598499Y1091050D03*
X598999Y1114550D03*
X603899Y1157850D03*
X597599Y1196050D03*
X596599Y1215050D03*
X600899Y1238650D03*
X598499Y1280550D03*
Y1261550D03*
X598999Y1292550D03*
X608899Y1305050D03*
X605599Y1326350D03*
X606199Y1338250D03*
X599499Y1351550D03*
X599999Y1382550D03*
X599499Y1370550D03*
X604899Y1407750D03*
X601299Y1447650D03*
X610899Y1496750D03*
X599799Y1544650D03*
X611900Y1577900D03*
X612499Y1615550D03*
X611999Y1603550D03*
X600599Y1645450D03*
X593399Y1668850D03*
X609499Y1675050D03*
Y1692050D03*
X607599Y1716450D03*
X606999Y1745550D03*
X593299Y1760950D03*
X608599Y1810750D03*
X595199Y1820910D03*
X611999Y1855950D03*
X591499D03*
X602799Y1887350D03*
Y1906350D03*
X601799Y1933850D03*
X602799Y1915350D03*
X601799Y1952850D03*
Y1961850D03*
X605299Y1975750D03*
X605999Y1987050D03*
X625999Y7050D03*
X624499Y23050D03*
X624999Y44550D03*
X624499Y61550D03*
X624999Y123550D03*
X624499Y143050D03*
Y162050D03*
X625499Y183050D03*
X623899Y202550D03*
X625499Y217550D03*
X627999Y262550D03*
Y248050D03*
Y280050D03*
X627499Y299550D03*
X628200Y320000D03*
X628499Y339550D03*
X632399Y358750D03*
X620999Y411550D03*
X621999Y432550D03*
X621499Y452050D03*
Y466550D03*
Y484050D03*
X613700Y504600D03*
X625999Y585050D03*
X620499Y623550D03*
Y609050D03*
X631999Y639650D03*
X622999Y672050D03*
Y689550D03*
X629099Y714050D03*
X633499Y750150D03*
X621499Y767150D03*
X621999Y835050D03*
X612999Y854550D03*
X629499Y853050D03*
Y868550D03*
X613499Y868050D03*
X616699Y948250D03*
Y967250D03*
X617699Y988250D03*
X631999Y1001550D03*
X629999Y1020050D03*
Y1034550D03*
Y1052050D03*
X629499Y1071550D03*
Y1090550D03*
X616499Y1115050D03*
X627699Y1143550D03*
X628699Y1164550D03*
X626199Y1183450D03*
X630499Y1243950D03*
X617599Y1246250D03*
X618199Y1268250D03*
X617599Y1260750D03*
X618199Y1296250D03*
Y1287250D03*
X631799Y1322650D03*
X617899Y1360850D03*
X632499Y1347950D03*
X625499Y1383450D03*
X627499Y1406050D03*
X626799Y1432350D03*
X625199Y1489150D03*
X617699Y1530350D03*
X623499Y1564050D03*
X633499Y1615450D03*
X628499Y1636650D03*
X627299Y1659550D03*
X625499Y1725050D03*
X619499Y1803150D03*
X627273Y1793905D03*
X626999Y1800050D03*
X632799Y1820450D03*
X627494Y1829068D03*
X627499Y1855950D03*
X630699Y1872750D03*
Y1891750D03*
Y1900750D03*
X616499Y1913050D03*
Y1894050D03*
X629699Y1919250D03*
X616499Y1922050D03*
X629699Y1947250D03*
Y1938250D03*
X615499Y1940550D03*
X622799Y1976250D03*
X615499Y1959550D03*
Y1968550D03*
X626999Y1987050D03*
X645499Y7050D03*
X651799Y40650D03*
Y59650D03*
X652799Y80650D03*
X649899Y138350D03*
Y157350D03*
X650899Y178350D03*
X642999Y218050D03*
X653999Y286550D03*
X635399Y376250D03*
X643599Y395950D03*
X644599Y416950D03*
X644099Y450950D03*
Y436450D03*
X642499Y525750D03*
X643499Y546750D03*
X642999Y566250D03*
X646999Y584550D03*
X640599Y604650D03*
X645099Y639150D03*
X647499Y657050D03*
Y671550D03*
X648999Y702350D03*
X647499Y689050D03*
X651999Y718350D03*
X647399Y742150D03*
X653099Y803350D03*
X645799Y816650D03*
X641599Y843250D03*
Y862250D03*
X642599Y883250D03*
X639499Y952150D03*
Y971150D03*
X633999Y1103050D03*
X641799Y1137650D03*
X650299Y1153150D03*
X651299Y1174150D03*
X650599Y1182050D03*
X651599Y1203050D03*
X638999Y1267550D03*
Y1286550D03*
Y1295550D03*
X654499Y1354050D03*
Y1373050D03*
X652999Y1403550D03*
Y1418050D03*
Y1435550D03*
X636799Y1461250D03*
X643099Y1541350D03*
X652399Y1575850D03*
X639200Y1576200D03*
X635500Y1603900D03*
X652499Y1618550D03*
Y1609550D03*
X649399Y1644950D03*
X635099Y1691150D03*
X642499Y1709050D03*
X650399Y1771250D03*
X642400Y1800100D03*
X633837Y1807384D03*
X640999Y1815550D03*
X644049Y1810834D03*
X645099Y1877550D03*
X645399Y1906150D03*
X646799Y1926450D03*
X644999Y1934050D03*
Y1953050D03*
X643799Y1976250D03*
X645499Y1965050D03*
X642499Y1987050D03*
X660999Y7050D03*
X674999Y20550D03*
X675499Y42050D03*
Y74550D03*
X674999Y59050D03*
X675499Y89050D03*
Y103550D03*
Y121050D03*
X674999Y140550D03*
Y159550D03*
X675999Y180550D03*
X662499Y218050D03*
X656499Y307050D03*
Y324550D03*
X655999Y344050D03*
X659899Y363250D03*
X666999Y476550D03*
Y491050D03*
Y508550D03*
X666499Y528050D03*
Y547050D03*
X667499Y568050D03*
X674999Y601550D03*
X665999Y623550D03*
X673999Y645150D03*
X665499Y766550D03*
X664999Y786050D03*
Y805050D03*
X665999Y826050D03*
X663999Y844550D03*
Y876550D03*
Y859050D03*
X663499Y896050D03*
Y915050D03*
X664499Y936050D03*
X658999Y959050D03*
X656999Y977550D03*
Y992050D03*
X673999Y1017550D03*
X656999Y1009550D03*
X673999Y1036550D03*
X656499Y1029050D03*
X674699Y1061450D03*
X656499Y1048050D03*
X674699Y1080450D03*
X669499Y1116550D03*
X674999Y1134950D03*
X667199Y1152850D03*
X668199Y1173850D03*
X670199Y1192750D03*
X671199Y1213750D03*
X668699Y1227650D03*
X657099Y1272850D03*
X657799Y1288450D03*
X672999Y1303450D03*
X656399Y1307050D03*
X671999Y1324950D03*
X665699Y1337250D03*
X654999Y1385050D03*
X659699Y1445950D03*
X665699Y1462250D03*
X656099Y1479550D03*
X672399Y1508750D03*
X673699Y1535350D03*
X662099Y1549650D03*
X670699Y1603150D03*
X671399Y1625350D03*
X657099Y1668850D03*
X674999Y1676550D03*
X656499Y1697050D03*
X675499Y1738050D03*
X665399Y1752350D03*
X675499Y1757050D03*
X675999Y1769050D03*
X659159Y1792278D03*
X659549Y1815384D03*
X667999Y1870950D03*
X669399Y1855350D03*
X674899Y1892350D03*
X661299Y1890050D03*
X674899Y1911350D03*
X661299Y1909050D03*
X674899Y1920350D03*
X661299Y1918050D03*
X673899Y1938850D03*
X660299Y1936550D03*
Y1955550D03*
X673899Y1966850D03*
Y1957850D03*
X660299Y1964550D03*
X659299Y1976250D03*
X661999Y1986550D03*
X680499Y6550D03*
X694999Y62650D03*
Y81650D03*
X695999Y102650D03*
X688999Y196550D03*
X677999Y218050D03*
X683499Y263050D03*
Y248550D03*
X680500Y280700D03*
X682999Y300050D03*
Y319050D03*
X683999Y340050D03*
X694999Y480550D03*
X695999Y501550D03*
X695499Y521050D03*
X691399Y548350D03*
X692399Y569350D03*
X691899Y588850D03*
X690499Y623050D03*
X693999Y648150D03*
X678499Y671050D03*
X679299Y703050D03*
X678499Y688550D03*
X681899Y713650D03*
X696299Y741850D03*
X694599Y763450D03*
X685999Y780050D03*
X687099Y804650D03*
Y823650D03*
X688099Y844650D03*
X687099Y896350D03*
Y915350D03*
X688099Y936350D03*
X678299Y978350D03*
Y997350D03*
X694999Y993050D03*
X692999Y1011550D03*
Y1026050D03*
Y1043550D03*
X692499Y1063050D03*
Y1082050D03*
X689999Y1105550D03*
X695999Y1203050D03*
Y1235050D03*
Y1217550D03*
X684299Y1249550D03*
X695999Y1323350D03*
X677999Y1347550D03*
X694999Y1360050D03*
X680299Y1365850D03*
X694999Y1379050D03*
X681299Y1393150D03*
X692999Y1406550D03*
X694999Y1388050D03*
X678299Y1425050D03*
X692999Y1421050D03*
X686999Y1468850D03*
X685299Y1551950D03*
X681299Y1579150D03*
X693599Y1602450D03*
X686699Y1638650D03*
X691999Y1660550D03*
X693099Y1722350D03*
X690499Y1744950D03*
X694599Y1768450D03*
X693549Y1793134D03*
X686473Y1818375D03*
X686999Y1870250D03*
X690899Y1855850D03*
X696299Y1898850D03*
X676399Y1901150D03*
X695299Y1926450D03*
X685499Y1940050D03*
X696299Y1976250D03*
X678799Y1975750D03*
X685499Y1959050D03*
Y1968050D03*
X679499Y1987050D03*
X697999Y7050D03*
X712499Y6050D03*
X699699Y141750D03*
Y160750D03*
X700699Y181750D03*
X711999Y218050D03*
X711499Y252550D03*
X711999Y307550D03*
Y293050D03*
Y325050D03*
X711499Y344550D03*
X712699Y434450D03*
X713699Y455450D03*
X713199Y474950D03*
Y489450D03*
X712599Y521050D03*
X713599Y542050D03*
X713099Y561550D03*
X699999Y610050D03*
X717099Y636050D03*
X702999Y656050D03*
Y688050D03*
Y670550D03*
X710899Y751150D03*
X716599Y736850D03*
X706999Y792550D03*
X707499Y773050D03*
X706999Y811550D03*
X707999Y832550D03*
X705999Y851050D03*
Y865550D03*
X707399Y899550D03*
Y918550D03*
X706499Y942550D03*
X713999Y1017050D03*
Y1031550D03*
X713499Y1068550D03*
X713999Y1049050D03*
X709999Y1105550D03*
X700499Y1118550D03*
X704299Y1132650D03*
X716999Y1148150D03*
X697499Y1153550D03*
X717999Y1169150D03*
X697499Y1172550D03*
X713399Y1178750D03*
X697999Y1184550D03*
X713599Y1214650D03*
X714399Y1199750D03*
X708699Y1243550D03*
X709699Y1264550D03*
X707899Y1346250D03*
X702299Y1404450D03*
X713899Y1386450D03*
X716899Y1459850D03*
X700899Y1450250D03*
X716199Y1503050D03*
X714599Y1533950D03*
X708899Y1549250D03*
X698599Y1568550D03*
X706700Y1579900D03*
X717099Y1702450D03*
X702599Y1730550D03*
X715999Y1744050D03*
X709099Y1751850D03*
X715999Y1763050D03*
Y1772050D03*
X706549Y1793634D03*
X717000Y1812384D03*
X705000Y1811900D03*
X711500Y1817700D03*
X704300Y1828400D03*
X697999Y1844550D03*
X706399Y1855850D03*
X705599Y1891850D03*
X716599Y1918450D03*
X698299Y1948050D03*
X711899Y1944050D03*
X709199Y1962950D03*
X717999Y1987550D03*
X702499D03*
X729999Y6550D03*
X725499Y23550D03*
X725999Y45050D03*
X725499Y62050D03*
X725999Y77550D03*
Y92050D03*
Y106550D03*
X738199Y137450D03*
X725999Y124050D03*
X725499Y143550D03*
Y162550D03*
X726499Y183550D03*
X728899Y204550D03*
X729499Y218550D03*
X723200Y275500D03*
X737999Y467050D03*
X738999Y488050D03*
X738499Y507550D03*
Y539550D03*
Y522050D03*
X737999Y559050D03*
X731499Y572050D03*
Y586550D03*
Y604050D03*
X721499Y617550D03*
X729699Y640350D03*
X723499Y654850D03*
X739399Y688150D03*
X720899Y712250D03*
X732499Y729250D03*
X727099Y715050D03*
X733799Y761450D03*
X723999Y783350D03*
Y802350D03*
X724999Y823350D03*
X728499Y841850D03*
X729999Y862850D03*
Y881850D03*
X730999Y902850D03*
X723699Y936250D03*
Y955250D03*
X724699Y976250D03*
X734999Y1030550D03*
Y1045050D03*
Y1062550D03*
X727499Y1106050D03*
X737999Y1119050D03*
X720499Y1118550D03*
X727499Y1132650D03*
X737999Y1159550D03*
Y1187550D03*
Y1178550D03*
X735999Y1206050D03*
X725499Y1231650D03*
X735999Y1220550D03*
X725499Y1250650D03*
X723499Y1278150D03*
X725499Y1259650D03*
X723499Y1292650D03*
X719199Y1322350D03*
X739199Y1348950D03*
X734199Y1373850D03*
X736199Y1399050D03*
X737799Y1428350D03*
X721899Y1419050D03*
X719499Y1446650D03*
X729199Y1492750D03*
X735799Y1533650D03*
X734499Y1563550D03*
X722199Y1564250D03*
X719999Y1605050D03*
X732999Y1620050D03*
X738799Y1677250D03*
X727399Y1694350D03*
X739199Y1716750D03*
X721199Y1723750D03*
X729999Y1756450D03*
X729499Y1778750D03*
X728099Y1844750D03*
X723199Y1867950D03*
X725899Y1855350D03*
X732999Y1868550D03*
X728299Y1888850D03*
X732199Y1878750D03*
X728799Y1908150D03*
Y1933050D03*
X736799Y1919450D03*
X730499Y1954650D03*
X721499Y1974550D03*
X737499Y1987050D03*
X749499Y6550D03*
X751499Y48350D03*
X757499Y44050D03*
Y63050D03*
X758499Y84050D03*
X752099Y112150D03*
X757999Y154550D03*
Y159050D03*
X753999Y154550D03*
Y159050D03*
X749499Y218550D03*
X755499Y314550D03*
X755346Y319149D03*
X751539Y313984D03*
X751499Y318050D03*
X749899Y398550D03*
X750899Y419550D03*
X750399Y453550D03*
Y439050D03*
X755199Y488150D03*
X756199Y509150D03*
X755699Y528650D03*
X754499Y564650D03*
X755499Y585650D03*
X754999Y605150D03*
X744999Y626550D03*
X751499Y679148D03*
X757400Y686300D03*
X747999Y670750D03*
X754999Y694050D03*
X749999Y700050D03*
X749499Y716050D03*
X744999Y715550D03*
X749999Y720050D03*
X745499D03*
X749799Y767450D03*
X743099Y785350D03*
X751999Y817050D03*
X751499Y855550D03*
Y836550D03*
X751599Y887350D03*
Y906350D03*
X752599Y927350D03*
X749999Y946550D03*
Y965550D03*
X751399Y1004550D03*
X750999Y986550D03*
X751399Y1023550D03*
X752399Y1052550D03*
X753999Y1100050D03*
X755499Y1119050D03*
X749999Y1119550D03*
X748999Y1115550D03*
X748499Y1111550D03*
X758799Y1171150D03*
Y1190150D03*
Y1199150D03*
X756799Y1232150D03*
Y1217650D03*
X757399Y1258650D03*
Y1239650D03*
X740499Y1252550D03*
X757399Y1267650D03*
X740499Y1270050D03*
X740799Y1298750D03*
X755399Y1300650D03*
Y1286150D03*
X742099Y1320650D03*
X754999Y1420050D03*
Y1437550D03*
X741099Y1450250D03*
Y1498150D03*
X747199Y1509150D03*
X755499Y1507550D03*
X751000Y1517000D03*
X757500Y1522500D03*
X751000Y1521000D03*
Y1525000D03*
X755499Y1568550D03*
X743400Y1578700D03*
X751300Y1604900D03*
X756299Y1679050D03*
X750099Y1694950D03*
X756499Y1712150D03*
X747499Y1734350D03*
X756900Y1766000D03*
X752900D03*
X751899Y1752150D03*
X747799Y1766750D03*
X751999Y1775550D03*
X756617Y1780067D03*
X752657Y1779496D03*
X755999Y1775550D03*
X753558Y1769946D03*
X757518Y1770517D03*
X744049Y1791634D03*
X740549Y1802634D03*
X753949Y1798194D03*
X740549Y1810384D03*
X747599Y1844250D03*
X744699Y1868450D03*
X758399Y1868350D03*
X743399Y1855850D03*
X743799Y1888850D03*
X753699Y1879250D03*
X755299Y1902150D03*
X739799D03*
X755500Y1914500D03*
X746499Y1974250D03*
X754999Y1987550D03*
X764999Y6550D03*
X763399Y24150D03*
X774399Y54050D03*
X775399Y80250D03*
X778399Y105250D03*
X767399Y140150D03*
X760799Y181950D03*
X779399Y200550D03*
X766999Y219050D03*
X781478Y363924D03*
X776978D03*
X772478Y359924D03*
Y363924D03*
X774999Y476550D03*
Y462050D03*
Y494050D03*
X774499Y513550D03*
Y532550D03*
X775499Y553550D03*
X777499Y638050D03*
X764599Y655750D03*
X777499Y664550D03*
X771800Y686600D03*
X766499Y699050D03*
Y705550D03*
X771196Y764382D03*
Y760382D03*
X775696Y764382D03*
X780196D03*
X778999Y806950D03*
X763099Y796350D03*
X775199Y839250D03*
Y858250D03*
X776199Y879250D03*
X772199Y920650D03*
Y939650D03*
X773199Y960650D03*
X776899Y988050D03*
Y1007050D03*
X777899Y1028050D03*
X760999Y1095550D03*
X773499Y1101050D03*
X769499D03*
X773499Y1105050D03*
X769499D03*
X780333Y1165892D03*
X775833D03*
X771333Y1161892D03*
Y1165892D03*
X762499Y1335550D03*
X779399Y1361850D03*
X762499Y1353050D03*
X773999Y1393450D03*
X763399Y1401450D03*
X769300Y1488100D03*
X779000Y1488400D03*
X771399Y1474550D03*
X770999Y1500050D03*
X780499D03*
X773499Y1509050D03*
X769499D03*
X778327Y1569796D03*
X773327Y1565796D03*
X773827Y1569796D03*
X768500Y1577500D03*
X776999Y1647650D03*
X765099Y1664950D03*
X770399Y1699650D03*
X779999Y1717050D03*
X770099Y1730350D03*
X779899Y1748150D03*
X765600Y1756800D03*
X767159Y1792364D03*
X765099Y1844750D03*
X779699Y1867950D03*
X779399Y1855850D03*
X763899D03*
X780799Y1888850D03*
X763299Y1888350D03*
X769199Y1879250D03*
X774499Y1908050D03*
X765999D03*
X773999Y1923550D03*
X767999Y1923050D03*
X774499Y1930050D03*
X768999D03*
X775999Y1916050D03*
X768499Y1917550D03*
X775814Y1975699D03*
X770814Y1971713D03*
X771814Y1975713D03*
X777499Y1987550D03*
X784499Y6050D03*
X801999Y6550D03*
X796999Y27050D03*
X797499Y48550D03*
X796999Y65550D03*
X797499Y81050D03*
Y95550D03*
Y110050D03*
X796599Y123450D03*
X797499Y127550D03*
X796999Y147050D03*
Y166050D03*
X797999Y187050D03*
X786499Y219050D03*
X800999Y216550D03*
X796873Y307571D03*
Y303071D03*
Y298571D03*
Y294071D03*
X784478Y355424D03*
Y359924D03*
X789999Y570050D03*
Y602050D03*
Y584550D03*
X785499Y641050D03*
X794999Y664550D03*
X786500Y686100D03*
X798000Y686400D03*
X782999Y699550D03*
X794331Y698353D03*
Y702853D03*
Y707353D03*
Y711853D03*
X799385Y761436D03*
X783196Y760382D03*
Y755882D03*
X802499Y814550D03*
X801999Y834050D03*
Y853050D03*
X800999Y892550D03*
Y907050D03*
Y924550D03*
X800499Y944050D03*
Y963050D03*
X801499Y984050D03*
X800999Y1005550D03*
Y1020050D03*
Y1037550D03*
X783999Y1096550D03*
X789499Y1099550D03*
X802499Y1097566D03*
X798499D03*
X783333Y1157392D03*
Y1161892D03*
X790999Y1194550D03*
Y1175550D03*
X791499Y1206550D03*
X789499Y1225050D03*
Y1257050D03*
Y1239550D03*
X788999Y1278150D03*
X791999Y1294450D03*
X795299Y1326650D03*
X799999Y1340550D03*
X798299Y1344250D03*
X799999Y1358050D03*
X781999Y1434650D03*
X786500Y1488600D03*
X801300Y1489000D03*
X786999Y1506550D03*
X795999Y1509550D03*
Y1504550D03*
Y1518550D03*
Y1514050D03*
X785827Y1561296D03*
Y1565796D03*
X782827Y1569796D03*
X797299Y1646650D03*
X802899Y1670550D03*
X782999Y1668050D03*
Y1687050D03*
X783499Y1699050D03*
X794499Y1734550D03*
X787900Y1758800D03*
X801099Y1844750D03*
X785599D03*
X791799Y1855850D03*
X797199Y1868450D03*
X788699Y1878750D03*
X783499Y1907050D03*
X790499Y1913050D03*
X795526Y1909696D03*
X795493Y1913696D03*
X795501Y1917696D03*
X795499Y1922050D03*
X783814Y1967213D03*
Y1971713D03*
X784016Y1975708D03*
X789299Y1983850D03*
X792999Y1987550D03*
X818999Y6050D03*
X817599Y43750D03*
X813299Y49350D03*
Y68350D03*
X814299Y89350D03*
X813299Y110850D03*
X821199Y137450D03*
X805899Y126150D03*
X809373Y307571D03*
Y297571D03*
Y292571D03*
X808999Y303050D03*
X821499Y314050D03*
X819299Y413250D03*
Y394250D03*
X820299Y434250D03*
X802999Y466050D03*
X803999Y487050D03*
X803499Y506550D03*
Y538550D03*
Y521050D03*
X802999Y558050D03*
X814499Y569550D03*
Y601550D03*
Y584050D03*
X809700Y686300D03*
X806300Y670600D03*
X806831Y701853D03*
Y706853D03*
X806999Y697050D03*
X806831Y711853D03*
X811499Y767550D03*
Y782050D03*
Y799550D03*
X802999Y874050D03*
X811499Y1097050D03*
X807499D03*
X807341Y1111216D03*
Y1101216D03*
X806999Y1106050D03*
X807341Y1116216D03*
X808299Y1175850D03*
X806599Y1189750D03*
X803599Y1211050D03*
X810199Y1229350D03*
Y1248350D03*
Y1257350D03*
X808199Y1275850D03*
Y1290350D03*
X822199Y1335250D03*
X819199Y1353550D03*
X806499Y1390550D03*
X803299Y1426650D03*
X806499Y1408050D03*
X805899Y1464250D03*
X809245Y1508722D03*
Y1503722D03*
Y1518722D03*
X808999Y1513550D03*
X813300Y1604100D03*
X803599Y1618350D03*
X814599Y1642650D03*
X823499Y1674050D03*
X808899Y1698450D03*
X823499Y1693050D03*
Y1702050D03*
X824100Y1719900D03*
X819400Y1721900D03*
X819200Y1727100D03*
X808299Y1755250D03*
X809299Y1856350D03*
X818900Y1870800D03*
X806199Y1879250D03*
X807936Y1914865D03*
Y1910365D03*
X807997Y1922865D03*
X808005Y1918865D03*
X813599Y1979950D03*
X812499Y1987050D03*
X836499Y6550D03*
X824899Y25150D03*
X844799Y19850D03*
X839999Y46050D03*
X840499Y55050D03*
X840999Y62550D03*
X841499Y71550D03*
X843499Y82550D03*
X838999Y85050D03*
X837999Y91050D03*
X838499Y107050D03*
Y99550D03*
X839499Y119050D03*
X837499Y138550D03*
X838499Y145050D03*
X838999Y313550D03*
X838499Y352050D03*
X839299Y390950D03*
Y409950D03*
X840299Y430950D03*
X824899Y500450D03*
X825899Y521450D03*
X825399Y540950D03*
X834599Y543050D03*
X835599Y564050D03*
X835099Y583550D03*
X841000Y671100D03*
X836149Y714050D03*
X835999Y767050D03*
X837799Y754150D03*
X835999Y781550D03*
Y799050D03*
X825199Y850850D03*
X827699Y873450D03*
Y892450D03*
X828699Y913450D03*
X826999Y963150D03*
Y982150D03*
X827999Y1003150D03*
X841999Y1118550D03*
X836149D03*
X839999Y1157550D03*
X831499Y1181550D03*
Y1209550D03*
Y1200550D03*
X829499Y1228050D03*
Y1242550D03*
X828199Y1267850D03*
X826199Y1294450D03*
X831499Y1324950D03*
X841999Y1341050D03*
Y1358550D03*
X825500Y1379000D03*
X834499Y1397550D03*
X836600Y1416500D03*
X843999Y1523550D03*
X839499D03*
X839899Y1562050D03*
X825999Y1578050D03*
X826499Y1609050D03*
X827199Y1622750D03*
X841499Y1638950D03*
X837199Y1660550D03*
X839199Y1683550D03*
X842799Y1701150D03*
X829200Y1719800D03*
X844499Y1788050D03*
X842500Y1799000D03*
X827999Y1791550D03*
X829799Y1856350D03*
X833199Y1868450D03*
X842199Y1879250D03*
X833100Y1878500D03*
X843999Y1928550D03*
X838999D03*
X840999Y1970550D03*
X829499Y1980250D03*
X829999Y1987550D03*
X855999Y6550D03*
X860799Y24150D03*
X865499Y39550D03*
X854499D03*
X856499Y71050D03*
X855499Y82050D03*
X845999Y111050D03*
X853999Y132550D03*
X865499Y125550D03*
X849999Y145550D03*
X863999Y313550D03*
X858400Y352300D03*
X847999Y352550D03*
X854499Y387550D03*
Y373050D03*
Y405050D03*
X853999Y424550D03*
Y443550D03*
X854999Y464550D03*
X860199Y525050D03*
X861199Y546050D03*
X860699Y565550D03*
X861800Y591200D03*
X860499Y607550D03*
X860796Y678632D03*
X859999Y713050D03*
Y767550D03*
X856299Y753150D03*
X846799Y754150D03*
X865000Y752100D03*
X859999Y782050D03*
Y799550D03*
X847799Y828250D03*
X857099Y873450D03*
X866199Y920350D03*
Y901350D03*
X850999Y962550D03*
Y943550D03*
X851999Y983550D03*
X859999Y1118550D03*
X846499Y1170450D03*
X856400Y1157700D03*
X848999Y1158050D03*
X863300Y1153800D03*
X845799Y1190450D03*
X849799Y1199750D03*
X851999Y1237550D03*
Y1218550D03*
X852499Y1249550D03*
X850499Y1268050D03*
X860099Y1295450D03*
X850499Y1300050D03*
Y1282550D03*
X861999Y1522550D03*
X850099Y1572250D03*
X858400Y1561900D03*
X850499Y1562050D03*
X865300Y1557700D03*
X864000Y1578200D03*
X849900Y1605100D03*
X852499Y1621350D03*
X855799Y1658250D03*
X855350Y1703201D03*
X864099Y1683550D03*
X853799Y1790850D03*
X863099Y1813150D03*
X862499Y1823550D03*
X854977Y1818994D03*
X861414Y1928550D03*
X864414Y1940050D03*
X850499Y1977950D03*
X856999Y1970050D03*
X849999Y1970550D03*
X865200Y1968000D03*
X864999Y1987050D03*
X849499D03*
X871499Y6550D03*
X885999Y21150D03*
X883999Y39050D03*
X881499Y70550D03*
X866999D03*
X876999Y82050D03*
X867499D03*
X886499Y99550D03*
Y104550D03*
X872499Y133050D03*
X875499Y125550D03*
X871499Y146050D03*
X871786Y218924D03*
Y203924D03*
X887400Y233555D03*
X871786Y233924D03*
X887400Y259700D03*
X879878Y247724D03*
X870600Y346700D03*
X875799Y386250D03*
Y405250D03*
X876799Y426250D03*
X884399Y443450D03*
Y462450D03*
X885399Y483450D03*
X870719Y609705D03*
X870773Y624705D03*
X870719Y639705D03*
X887401Y665000D03*
X881125Y652050D03*
X871786Y679436D03*
Y709482D03*
X871499Y689436D03*
X866499Y724550D03*
X871385Y719436D03*
X884499Y767050D03*
Y781550D03*
Y799050D03*
X873999Y830550D03*
Y845050D03*
Y862550D03*
X886999Y907350D03*
X867199Y941350D03*
X886999Y947250D03*
X870777Y1014948D03*
X870468Y1030227D03*
X886919Y1044478D03*
X870298Y1045227D03*
X880033Y1058592D03*
X887400Y1070600D03*
X871399Y1182850D03*
Y1201850D03*
Y1210850D03*
X869399Y1229350D03*
Y1243850D03*
X872099Y1268150D03*
X871399Y1291450D03*
X875399Y1322650D03*
X873499Y1356050D03*
X868499Y1392550D03*
Y1410050D03*
X871836Y1420460D03*
X886913Y1449010D03*
X871836Y1435460D03*
X879727Y1463696D03*
X871836Y1450460D03*
X887499Y1476050D03*
X873099Y1572550D03*
X886900Y1604100D03*
X866499Y1603050D03*
Y1612050D03*
X868099Y1635650D03*
X887299Y1620050D03*
X877699Y1646650D03*
X882999Y1678250D03*
X879200Y1698700D03*
X879900Y1709300D03*
X883900Y1709500D03*
X875900D03*
X882700Y1738300D03*
X886900Y1737900D03*
X872950Y1744401D03*
X866699Y1770950D03*
X879399Y1798150D03*
X869634Y1826876D03*
X871836Y1840972D03*
X887499Y1855550D03*
X869999Y1855972D03*
X887401Y1881500D03*
X879399Y1974550D03*
X873399Y1963650D03*
X868699Y1983250D03*
X884499Y1986550D03*
X890999Y6050D03*
X908499Y6550D03*
X902999Y22050D03*
X902499Y35050D03*
X905499Y56550D03*
X904999Y61550D03*
X904499Y74050D03*
X904999Y67550D03*
X890459Y100116D03*
X890499Y104550D03*
X889999Y132550D03*
X891999Y146050D03*
X906999Y243150D03*
Y224150D03*
X907999Y264150D03*
X906399Y295250D03*
Y314250D03*
X907399Y335250D03*
X904999Y370550D03*
Y385050D03*
Y402550D03*
X904499Y422050D03*
Y441050D03*
X905499Y462050D03*
X903999Y574378D03*
X898999Y622050D03*
Y604550D03*
X894000Y642400D03*
X900999Y652550D03*
Y670050D03*
X895999Y702550D03*
Y720050D03*
X898499Y830050D03*
Y844550D03*
X889699Y876050D03*
X898499Y862050D03*
X897299Y1182450D03*
X887999Y1209350D03*
X892499Y1224550D03*
Y1252550D03*
Y1243550D03*
X890499Y1271050D03*
Y1285550D03*
X890999Y1336550D03*
Y1354050D03*
X894499Y1423550D03*
Y1441050D03*
X895499Y1488050D03*
X902759Y1509585D03*
X894499Y1522050D03*
Y1539550D03*
X907500Y1604000D03*
X895999Y1661250D03*
X903599Y1686850D03*
X893200Y1721300D03*
X902900Y1709800D03*
X893200Y1730000D03*
X904814Y1789113D03*
X903299Y1814750D03*
X894999Y1829050D03*
X905299Y1852650D03*
X894000Y1868452D03*
X900299Y1876950D03*
X897299Y1904150D03*
X907599Y1930050D03*
X897599Y1938750D03*
X904299Y1954950D03*
X901999Y1987050D03*
X923999Y6050D03*
X917499Y21550D03*
X909499D03*
X909999Y35550D03*
X916499Y36050D03*
X928499Y51550D03*
X920900Y54700D03*
X928999Y56050D03*
X928499Y60550D03*
X928999Y65550D03*
X913699Y484650D03*
Y503650D03*
X914699Y524650D03*
X918999Y641550D03*
Y656050D03*
Y673550D03*
X918499Y693050D03*
Y712050D03*
X921899Y744850D03*
X919499Y733050D03*
X921899Y759350D03*
Y776850D03*
X921399Y796350D03*
X922399Y836350D03*
X921399Y815350D03*
X920399Y854850D03*
Y869350D03*
Y886850D03*
X919899Y906350D03*
Y925350D03*
X920899Y946350D03*
X921499Y999050D03*
Y1013550D03*
Y1031050D03*
X920999Y1050550D03*
Y1069550D03*
X925499Y1103550D03*
X921999Y1090550D03*
X925499Y1118050D03*
Y1135550D03*
X924999Y1174050D03*
Y1155050D03*
X925999Y1195050D03*
Y1207050D03*
Y1221550D03*
Y1239050D03*
X925499Y1258550D03*
Y1277550D03*
X926499Y1298550D03*
X928499Y1325350D03*
X925999Y1365050D03*
Y1379550D03*
Y1397050D03*
X925499Y1416550D03*
Y1435550D03*
X926499Y1456550D03*
X924999Y1485550D03*
Y1471050D03*
Y1503050D03*
X914599Y1521650D03*
X924499Y1522550D03*
X910899Y1549250D03*
X924499Y1541550D03*
X909700Y1576400D03*
X925499Y1562550D03*
X925599Y1612050D03*
X923599Y1634350D03*
X908899Y1630050D03*
X914899Y1657550D03*
X922599Y1682150D03*
X911299Y1800850D03*
X928000Y1818500D03*
X922899Y1853650D03*
X914999Y1868050D03*
Y1887050D03*
X914899Y1912450D03*
X915499Y1899050D03*
X916599Y1942650D03*
X914899Y1972250D03*
X921499Y1986550D03*
X941499Y6550D03*
X929999Y32550D03*
X940499Y33050D03*
X945499Y33550D03*
X943499Y48050D03*
Y55050D03*
Y72550D03*
X942999Y61550D03*
Y66550D03*
X943499Y78050D03*
X939199Y142050D03*
X932499Y191550D03*
Y206050D03*
Y223550D03*
X931999Y243050D03*
Y262050D03*
X932999Y283050D03*
X933499Y304050D03*
Y318550D03*
Y336050D03*
X932999Y355550D03*
Y374550D03*
X933999Y395550D03*
X933499Y429550D03*
Y415050D03*
Y447050D03*
X932999Y466550D03*
Y485550D03*
X933999Y506550D03*
X935499Y539050D03*
Y524550D03*
Y556550D03*
X934999Y576050D03*
X950299Y599650D03*
X934999Y595050D03*
X950299Y614150D03*
X935999Y616050D03*
X950299Y631650D03*
X949799Y651150D03*
Y670150D03*
X950799Y691150D03*
X944499Y750050D03*
Y735550D03*
Y767550D03*
X943999Y787050D03*
Y806050D03*
X944999Y827050D03*
X942999Y845550D03*
Y877550D03*
Y860050D03*
X942499Y897050D03*
Y916050D03*
X943499Y937050D03*
X949299Y977450D03*
Y991950D03*
Y1009450D03*
X948799Y1047950D03*
Y1028950D03*
X949799Y1068950D03*
Y1080950D03*
X950699Y1107750D03*
Y1122250D03*
Y1139750D03*
X950199Y1159250D03*
Y1178250D03*
X950699Y1262750D03*
Y1281750D03*
X943799Y1342950D03*
Y1380850D03*
X944000Y1391900D03*
X946700Y1426500D03*
X944000Y1511300D03*
X943199Y1531650D03*
X933199Y1577550D03*
X944499Y1632650D03*
X950100Y1626100D03*
X940499Y1656950D03*
X941499Y1679550D03*
X931499Y1702050D03*
X949799Y1756250D03*
X941800Y1787700D03*
X941499Y1776250D03*
X934200Y1793500D03*
X932199Y1801850D03*
X937199Y1869950D03*
X937499Y1893850D03*
X938199Y1917150D03*
X947499Y1936050D03*
X930999Y1931050D03*
X945199Y1946350D03*
X930999Y1950050D03*
X946199Y1966650D03*
X931499Y1962050D03*
X930199Y1979550D03*
X936999Y1986550D03*
X960999Y6550D03*
X954799Y17850D03*
X965999Y47050D03*
Y56050D03*
Y64050D03*
X966499Y73050D03*
Y82050D03*
X968399Y137150D03*
X967399Y180350D03*
X958799Y167350D03*
X956099Y181350D03*
X952799Y199150D03*
Y213650D03*
Y231150D03*
X952299Y250650D03*
Y269650D03*
X953299Y290650D03*
X952799Y324650D03*
Y310150D03*
Y342150D03*
X952299Y361650D03*
Y380650D03*
X953299Y401650D03*
X954799Y434150D03*
Y419650D03*
Y451650D03*
X966199Y473350D03*
Y492350D03*
X951799Y489650D03*
X967199Y513350D03*
X951799Y504150D03*
Y521650D03*
X951299Y560150D03*
Y541150D03*
X966799Y566350D03*
X952299Y581150D03*
X966799Y585350D03*
X967799Y606350D03*
X969499Y639050D03*
Y653550D03*
Y671050D03*
X968999Y709550D03*
Y690550D03*
X969999Y730550D03*
Y744250D03*
Y758750D03*
Y776250D03*
X969499Y795750D03*
Y814750D03*
X970499Y835750D03*
Y847750D03*
Y862250D03*
X969999Y899250D03*
X970499Y879750D03*
X969999Y918250D03*
X970999Y939250D03*
X971999Y996550D03*
Y1011050D03*
Y1028550D03*
X971499Y1067050D03*
Y1048050D03*
X951199Y1211250D03*
Y1199250D03*
Y1225750D03*
Y1243250D03*
X951699Y1302750D03*
X965099Y1324350D03*
X952499Y1361850D03*
X964400Y1409700D03*
X972000Y1442000D03*
Y1437500D03*
X971700Y1448300D03*
X962500Y1436500D03*
Y1441000D03*
X952800Y1437500D03*
Y1442000D03*
X962200Y1447300D03*
X952500Y1448300D03*
X971500Y1467500D03*
X971700Y1457800D03*
Y1462300D03*
Y1452800D03*
X962000Y1466500D03*
X952300Y1467500D03*
X962200Y1451800D03*
X952500Y1452800D03*
X962200Y1456800D03*
Y1461300D03*
X952500Y1457800D03*
Y1462300D03*
X966000Y1475000D03*
X958800Y1472500D03*
X966000Y1479500D03*
Y1484000D03*
X958800Y1477000D03*
Y1481500D03*
X965700Y1489300D03*
X958500Y1486800D03*
X960200Y1495300D03*
X951500D03*
X960049Y1500300D03*
X951349D03*
X960049Y1504800D03*
X951349D03*
X966600Y1529100D03*
X961400Y1528700D03*
X961900Y1522400D03*
X967100Y1522800D03*
X962100Y1516000D03*
X967300Y1516400D03*
X961600Y1534400D03*
X972000Y1547500D03*
X966100D03*
X960900Y1547100D03*
X961400Y1540800D03*
X966600Y1541200D03*
X966800Y1534800D03*
X961600Y1552900D03*
X966800Y1553300D03*
X972000Y1566000D03*
X966100D03*
X960900Y1565600D03*
X961400Y1559300D03*
X966600Y1559700D03*
X961900Y1572400D03*
X967100Y1572800D03*
X966400Y1585500D03*
X961200Y1585100D03*
X961700Y1578800D03*
X966900Y1579200D03*
X966500Y1592000D03*
X961300Y1591600D03*
X966300Y1598400D03*
X961100Y1598000D03*
X960600Y1604300D03*
X971700Y1604700D03*
X965800D03*
X957799Y1646950D03*
X955499Y1690850D03*
X958799Y1715750D03*
X965349Y1742000D03*
X954499Y1783550D03*
X971000Y1803000D03*
X971500Y1871500D03*
X966799Y1892150D03*
X955499Y1893050D03*
Y1902050D03*
X954099Y1915450D03*
X955799Y1951950D03*
X971499Y1956050D03*
Y1937050D03*
X953799Y1977950D03*
X971499Y1965050D03*
X956499Y1986050D03*
X976499Y6550D03*
X974699Y21450D03*
X991399Y22450D03*
X977399Y44050D03*
X974699Y64650D03*
X991999Y56050D03*
X983099Y83650D03*
X977699Y109150D03*
X981099Y123450D03*
X988699Y174350D03*
X982999Y189050D03*
Y203550D03*
Y221050D03*
X982499Y240550D03*
Y259550D03*
X983499Y280550D03*
X983999Y301550D03*
Y316050D03*
Y333550D03*
X983499Y353050D03*
Y372050D03*
X983999Y412550D03*
X984499Y393050D03*
X983999Y427050D03*
Y444550D03*
X983499Y464050D03*
Y483050D03*
X984499Y504050D03*
X985999Y536550D03*
Y522050D03*
Y554050D03*
X985499Y573550D03*
Y592550D03*
X986499Y613550D03*
X992999Y894550D03*
Y913550D03*
X972499Y1088050D03*
X975999Y1101050D03*
Y1115550D03*
X975499Y1152550D03*
X975999Y1133050D03*
X975499Y1171550D03*
X976499Y1192550D03*
Y1204550D03*
Y1219050D03*
Y1236550D03*
X975999Y1256050D03*
Y1275050D03*
X976999Y1296050D03*
X975100Y1342600D03*
X976499Y1362550D03*
Y1377050D03*
X992500Y1397300D03*
X973500Y1483000D03*
Y1478500D03*
X973200Y1488300D03*
X973500Y1474000D03*
X972549Y1502300D03*
Y1506800D03*
X972700Y1497300D03*
X973200Y1516400D03*
X972500Y1529100D03*
X973000Y1522800D03*
X972700Y1534800D03*
X972500Y1541200D03*
X972700Y1553300D03*
X972500Y1559700D03*
X973000Y1572800D03*
X972300Y1585500D03*
X972800Y1579200D03*
X972400Y1592000D03*
X972200Y1598400D03*
X989999Y1718050D03*
X993299Y1734350D03*
X976600Y1757100D03*
X976399Y1772250D03*
Y1791150D03*
X974699Y1914450D03*
X991999Y1915750D03*
X992299Y1929050D03*
X980999Y1933350D03*
X987999Y1949050D03*
Y1971950D03*
X989999Y1962650D03*
X973999Y1986550D03*
X995999Y6050D03*
X1013499Y6550D03*
X1002699Y40050D03*
X1005299Y71350D03*
X994399Y101250D03*
X1010599Y115550D03*
X1005299Y179950D03*
Y194450D03*
Y211950D03*
X1004799Y231450D03*
Y250450D03*
X1005799Y271450D03*
X1005299Y305450D03*
Y290950D03*
Y322950D03*
X1004799Y342450D03*
Y361450D03*
X1005799Y382450D03*
X1007299Y400450D03*
Y432450D03*
Y414950D03*
X1000699Y463350D03*
Y482350D03*
X1001699Y503350D03*
X1003999Y526850D03*
X1003499Y546350D03*
Y565350D03*
X1004499Y586350D03*
X1005999Y618850D03*
Y604350D03*
Y636350D03*
X994999Y747550D03*
Y733050D03*
Y765050D03*
X994499Y784550D03*
Y803550D03*
X995499Y824550D03*
X993499Y857550D03*
Y843050D03*
Y875050D03*
X994499Y941550D03*
X993999Y934550D03*
X994499Y956050D03*
Y973550D03*
X993999Y993050D03*
Y1012050D03*
X994999Y1033050D03*
Y1045050D03*
X998599Y1110950D03*
Y1096450D03*
Y1128450D03*
X998099Y1147950D03*
Y1166950D03*
X999099Y1187950D03*
Y1214450D03*
Y1199950D03*
Y1231950D03*
X998599Y1251450D03*
Y1270450D03*
X999599Y1291450D03*
X996500Y1324800D03*
X1000700Y1358100D03*
X994200Y1421500D03*
X1008999Y1702450D03*
X1008599Y1716050D03*
X994999Y1748950D03*
X999999Y1775250D03*
X1009999Y1797450D03*
X993499Y1805550D03*
X1007599Y1818450D03*
X993499Y1824550D03*
X1003599Y1846650D03*
X993499Y1833550D03*
X1011299Y1860650D03*
X995699Y1858950D03*
X1001599Y1921450D03*
X1000999Y1946350D03*
X1002500Y1953500D03*
X1005000Y1980500D03*
X994999Y1986550D03*
X1022000Y15500D03*
X1020499Y50550D03*
X1020999Y33050D03*
Y70050D03*
Y85550D03*
Y105050D03*
X1020499Y122550D03*
X1020999Y158550D03*
X1021499Y141050D03*
Y178050D03*
Y193550D03*
Y213050D03*
X1020999Y230550D03*
Y252050D03*
X1020499Y269550D03*
X1020999Y304550D03*
Y289050D03*
Y324050D03*
X1020499Y341550D03*
Y391550D03*
X1020999Y374050D03*
Y411050D03*
Y426550D03*
Y446050D03*
X1020499Y463550D03*
X1021999Y486550D03*
X1021499Y504050D03*
X1021999Y539050D03*
Y523550D03*
Y558550D03*
X1021499Y576050D03*
X1020499Y623050D03*
X1020999Y605550D03*
Y642550D03*
Y658050D03*
Y677550D03*
X1020499Y695050D03*
X1020999Y720050D03*
X1020499Y737550D03*
X1020999Y772550D03*
Y757050D03*
Y792050D03*
X1020499Y809550D03*
Y828050D03*
X1019999Y845550D03*
X1020499Y865050D03*
Y880550D03*
X1019999Y917550D03*
X1020499Y900050D03*
X1019999Y934050D03*
X1019499Y951550D03*
X1019999Y971050D03*
Y986550D03*
X1019499Y1023550D03*
X1019999Y1006050D03*
Y1043050D03*
Y1058550D03*
X1020499Y1081550D03*
X1019999Y1099050D03*
X1020499Y1118550D03*
Y1134050D03*
X1019499Y1146050D03*
X1018999Y1163550D03*
X1019499Y1183050D03*
Y1198550D03*
X1016999Y1219050D03*
X1016499Y1236550D03*
X1016999Y1256050D03*
Y1271550D03*
X1016499Y1301050D03*
X1022599Y1322950D03*
X1023300Y1344400D03*
X1024300Y1365200D03*
Y1393600D03*
X1022299Y1715750D03*
X1016899Y1731650D03*
X1020299Y1746650D03*
X1015299Y1765950D03*
X1026899Y1768550D03*
X1022999Y1784550D03*
X1022499Y1802050D03*
X1022999Y1821550D03*
Y1837050D03*
X1020999Y1860050D03*
X1020499Y1877550D03*
X1020999Y1912550D03*
Y1897050D03*
X1017499Y1954550D03*
X1017999Y1937050D03*
X1023000Y1973000D03*
X1017999Y1987050D03*
X1234250Y1685950D03*
G54D21*
G01X-53190Y-209897D02*
Y-192397D01*
G01X-44894D02*
X-53190Y-203189D01*
G01X-43584Y-209897D02*
X-49479Y-198231D01*
G01X-35909Y-209897D02*
Y-192397D01*
X-25865Y-209897D01*
Y-192397D01*
G01X-13387Y-209897D02*
X-15134Y-209605D01*
X-16662Y-208439D01*
X-17972Y-206689D01*
X-18846Y-204647D01*
X-19282Y-202314D01*
Y-199980D01*
X-18846Y-197647D01*
X-17972Y-195605D01*
X-16662Y-193856D01*
X-15134Y-192689D01*
X-13387Y-192397D01*
X-11641Y-192689D01*
X-10112Y-193856D01*
X-8802Y-195605D01*
X-7928Y-197647D01*
X-7492Y-199980D01*
Y-202314D01*
X-7928Y-204647D01*
X-8802Y-206689D01*
X-10112Y-208439D01*
X-11641Y-209605D01*
X-13387Y-209897D01*
G01X-472D02*
X8698Y-192397D01*
G01X-472D02*
X8698Y-209897D01*
G01X34310D02*
Y-192397D01*
X38676D01*
X40423Y-193272D01*
X41733Y-194439D01*
X42825Y-196188D01*
X43698Y-198231D01*
X43916Y-201147D01*
X43698Y-204064D01*
X42825Y-206106D01*
X41733Y-207856D01*
X40423Y-209022D01*
X38676Y-209897D01*
X34310D01*
G01X52246D02*
Y-192397D01*
X57705D01*
X59451Y-193272D01*
X60543Y-194439D01*
X60980Y-196772D01*
X60543Y-199106D01*
X59233Y-200564D01*
X57705Y-201439D01*
X52246D01*
G01X57705D02*
X60980Y-209897D01*
G01X71493Y-192397D02*
X76733D01*
G01X74113D02*
Y-209897D01*
G01X71493D02*
X76733D01*
G01X86154Y-192397D02*
X91613Y-209897D01*
X97072Y-192397D01*
G01X113480Y-209897D02*
X104746D01*
Y-192397D01*
X113480D01*
G01X109986Y-200855D02*
X104746D01*
G01X139746Y-209897D02*
Y-192397D01*
X144986D01*
X146733Y-193272D01*
X148043Y-195314D01*
X148480Y-197647D01*
X148043Y-199980D01*
X146951Y-201730D01*
X144986Y-202606D01*
X139746D01*
G01X157246Y-192397D02*
Y-209897D01*
X165980D01*
G01X173654D02*
X179113Y-192397D01*
X184572Y-209897D01*
G01X182606Y-203772D02*
X175619D01*
G01X191591Y-209897D02*
Y-192397D01*
X201635Y-209897D01*
Y-192397D01*
G01X218480Y-209897D02*
X209746D01*
Y-192397D01*
X218480D01*
G01X214986Y-200855D02*
X209746D01*
G01X250859Y-200564D02*
X251733Y-199689D01*
X252388Y-198231D01*
X252825Y-196188D01*
X252388Y-194439D01*
X251515Y-193272D01*
X249986Y-192397D01*
X244091D01*
Y-209897D01*
X251296D01*
X252825Y-208731D01*
X253698Y-206980D01*
X254135Y-204939D01*
X253698Y-202897D01*
X252388Y-201147D01*
X250859Y-200564D01*
X244091D01*
G01X266613Y-209897D02*
X264866Y-209605D01*
X263338Y-208439D01*
X262028Y-206689D01*
X261154Y-204647D01*
X260718Y-202314D01*
Y-199980D01*
X261154Y-197647D01*
X262028Y-195605D01*
X263338Y-193856D01*
X264866Y-192689D01*
X266613Y-192397D01*
X268359Y-192689D01*
X269888Y-193856D01*
X271198Y-195605D01*
X272072Y-197647D01*
X272508Y-199980D01*
Y-202314D01*
X272072Y-204647D01*
X271198Y-206689D01*
X269888Y-208439D01*
X268359Y-209605D01*
X266613Y-209897D01*
G01X278654D02*
X284113Y-192397D01*
X289572Y-209897D01*
G01X287606Y-203772D02*
X280619D01*
G01X297246Y-209897D02*
Y-192397D01*
X302705D01*
X304451Y-193272D01*
X305543Y-194439D01*
X305980Y-196772D01*
X305543Y-199106D01*
X304233Y-200564D01*
X302705Y-201439D01*
X297246D01*
G01X302705D02*
X305980Y-209897D01*
G01X314310D02*
Y-192397D01*
X318676D01*
X320423Y-193272D01*
X321733Y-194439D01*
X322825Y-196188D01*
X323698Y-198231D01*
X323916Y-201147D01*
X323698Y-204064D01*
X322825Y-206106D01*
X321733Y-207856D01*
X320423Y-209022D01*
X318676Y-209897D01*
X314310D01*
G01X68771Y18647D02*
Y27074D01*
G01X67271Y23647D02*
X68771Y18647D01*
X70271Y23647D01*
X67271D01*
G01X66748Y18647D02*
X71048D01*
G02Y15447I0J-1600D01*
G01X66748D01*
G02Y18647I0J1600D01*
G01X67218Y183670D02*
X68718Y188670D01*
X70218Y183670D01*
X67218D01*
G01X68718Y188670D02*
Y180243D01*
G01X66748Y191875D02*
X71048D01*
G02Y188675I0J-1600D01*
G01X66748D01*
G02Y191875I0J1600D01*
G01X68771Y424159D02*
Y432586D01*
G01X67271Y429159D02*
X68771Y424159D01*
X70271Y429159D01*
X67271D01*
G01X66748Y424159D02*
X71048D01*
G02Y420959I0J-1600D01*
G01X66748D01*
G02Y424159I0J1600D01*
G01X67218Y589182D02*
X68718Y594182D01*
X70218Y589182D01*
X67218D01*
G01X68718Y594182D02*
Y585755D01*
G01X66748Y597387D02*
X71048D01*
G02Y594187I0J-1600D01*
G01X66748D01*
G02Y597387I0J1600D01*
G01X68771Y829671D02*
Y838098D01*
G01X67271Y834671D02*
X68771Y829671D01*
X70271Y834671D01*
X67271D01*
G01X66748Y829671D02*
X71048D01*
G02Y826471I0J-1600D01*
G01X66748D01*
G02Y829671I0J1600D01*
G01X67218Y994694D02*
X68718Y999694D01*
X70218Y994694D01*
X67218D01*
G01X68718Y999694D02*
Y991267D01*
G01X66748Y1002899D02*
X71048D01*
G02Y999699I0J-1600D01*
G01X66748D01*
G02Y1002899I0J1600D01*
G01X68771Y1235183D02*
Y1243610D01*
G01X67271Y1240183D02*
X68771Y1235183D01*
X70271Y1240183D01*
X67271D01*
G01X66748Y1235183D02*
X71048D01*
G02Y1231983I0J-1600D01*
G01X66748D01*
G02Y1235183I0J1600D01*
G01X67218Y1400206D02*
X68718Y1405206D01*
X70218Y1400206D01*
X67218D01*
G01X68718Y1405206D02*
Y1396779D01*
G01X66748Y1408411D02*
X71048D01*
G02Y1405211I0J-1600D01*
G01X66748D01*
G02Y1408411I0J1600D01*
G01Y1640695D02*
X71048D01*
G02Y1637495I0J-1600D01*
G01X66748D01*
G02Y1640695I0J1600D01*
G01X68771D02*
Y1649122D01*
G01X67271Y1645695D02*
X68771Y1640695D01*
X70271Y1645695D01*
X67271D01*
G01X67218Y1805718D02*
X68718Y1810718D01*
X70218Y1805718D01*
X67218D01*
G01X68718Y1810718D02*
Y1802291D01*
G01X66748Y1813923D02*
X71048D01*
G02Y1810723I0J-1600D01*
G01X66748D01*
G02Y1813923I0J1600D01*
G01X94686Y-164897D02*
Y-147397D01*
X100363Y-161980D01*
X106040Y-147397D01*
Y-164897D01*
G01X117863D02*
X116553Y-164605D01*
X115243Y-163439D01*
X114369Y-161397D01*
X113933Y-159064D01*
X114369Y-156730D01*
X115243Y-154689D01*
X116553Y-153522D01*
X117863Y-153231D01*
X119173Y-153522D01*
X120483Y-154689D01*
X121356Y-156730D01*
X121575Y-159064D01*
X121356Y-161397D01*
X120483Y-163439D01*
X119173Y-164605D01*
X117863Y-164897D01*
G01X139293Y-147397D02*
Y-164897D01*
G01Y-162273D02*
X138420Y-163731D01*
X137109Y-164605D01*
X135581Y-164897D01*
X133835Y-164314D01*
X132525Y-162856D01*
X131651Y-161106D01*
X131433Y-159064D01*
X131651Y-157022D01*
X132525Y-155272D01*
X133835Y-153814D01*
X135581Y-153231D01*
X137109Y-153522D01*
X138201Y-154106D01*
X139293Y-155272D01*
G01X149588Y-157022D02*
X156575D01*
X155920Y-154980D01*
X154828Y-153814D01*
X153300Y-153231D01*
X151771Y-153522D01*
X150461Y-154397D01*
X149588Y-156439D01*
X149151Y-158189D01*
Y-159939D01*
X149588Y-161689D01*
X150680Y-163439D01*
X151990Y-164605D01*
X153518Y-164897D01*
X155046Y-164314D01*
X156575Y-162564D01*
G01X170363Y-164897D02*
Y-147397D01*
G01X169473Y178203D02*
X165173D01*
G02Y181403I0J1600D01*
G01X169473D01*
G02Y178203I0J-1600D01*
G01X169003Y186408D02*
X167503Y181408D01*
X166003Y186408D01*
X169003D01*
G01X168950Y346431D02*
X167450Y351431D01*
X165950Y346431D01*
X168950D01*
G01X169473Y351431D02*
X165173D01*
G02Y354631I0J1600D01*
G01X169473D01*
G02Y351431I0J-1600D01*
G01X169003Y591920D02*
X167503Y586920D01*
X166003Y591920D01*
X169003D01*
G01X169473Y583715D02*
X165173D01*
G02Y586915I0J1600D01*
G01X169473D01*
G02Y583715I0J-1600D01*
G01X168950Y751943D02*
X167450Y756943D01*
X165950Y751943D01*
X168950D01*
G01X169473Y756943D02*
X165173D01*
G02Y760143I0J1600D01*
G01X169473D01*
G02Y756943I0J-1600D01*
G01X169003Y997432D02*
X167503Y992432D01*
X166003Y997432D01*
X169003D01*
G01X169473Y989227D02*
X165173D01*
G02Y992427I0J1600D01*
G01X169473D01*
G02Y989227I0J-1600D01*
G01X168950Y1157455D02*
X167450Y1162455D01*
X165950Y1157455D01*
X168950D01*
G01X169473Y1162455D02*
X165173D01*
G02Y1165655I0J1600D01*
G01X169473D01*
G02Y1162455I0J-1600D01*
G01X169003Y1402944D02*
X167503Y1397944D01*
X166003Y1402944D01*
X169003D01*
G01X169473Y1394739D02*
X165173D01*
G02Y1397939I0J1600D01*
G01X169473D01*
G02Y1394739I0J-1600D01*
G01X168950Y1562967D02*
X167450Y1567967D01*
X165950Y1562967D01*
X168950D01*
G01X169473Y1567967D02*
X165173D01*
G02Y1571167I0J1600D01*
G01X169473D01*
G02Y1567967I0J-1600D01*
G01X169003Y1808456D02*
X167503Y1803456D01*
X166003Y1808456D01*
X169003D01*
G01X169473Y1800251D02*
X165173D01*
G02Y1803451I0J1600D01*
G01X169473D01*
G02Y1800251I0J-1600D01*
G01X168950Y1968479D02*
X167450Y1973479D01*
X165950Y1968479D01*
X168950D01*
G01X169473Y1973479D02*
X165173D01*
G02Y1976679I0J1600D01*
G01X169473D01*
G02Y1973479I0J-1600D01*
G01X167503Y181408D02*
Y189835D01*
G01X167450Y351431D02*
Y343004D01*
G01X167503Y586920D02*
Y595347D01*
G01X167450Y756943D02*
Y748516D01*
G01X167503Y992432D02*
Y1000859D01*
G01X167450Y1162455D02*
Y1154028D01*
G01X167503Y1397944D02*
Y1406371D01*
G01X167450Y1567967D02*
Y1559540D01*
G01X167503Y1803456D02*
Y1811883D01*
G01X167450Y1973479D02*
Y1965052D01*
G01X376163Y-209897D02*
Y-192397D01*
X373543Y-195897D01*
G01Y-209897D02*
X378783D01*
G01X389515Y-195314D02*
X390825Y-193564D01*
X392353Y-192689D01*
X394100Y-192397D01*
X396283Y-192980D01*
X397811Y-194439D01*
X398248Y-196188D01*
X398030Y-197939D01*
X397156Y-199397D01*
X392790Y-202314D01*
X390825Y-204355D01*
X389515Y-207273D01*
X389078Y-209897D01*
X398248D01*
G01X413783D02*
Y-192397D01*
X405704Y-204939D01*
X416622D01*
G01X423860Y-206397D02*
X425169Y-208439D01*
X426916Y-209605D01*
X428881Y-209897D01*
X430628Y-209605D01*
X432375Y-208147D01*
X433466Y-206397D01*
X433685Y-204647D01*
X433248Y-202606D01*
X431720Y-201147D01*
X430191Y-200564D01*
X428226D01*
G01X430191D02*
X431501Y-199689D01*
X432593Y-198231D01*
X433030Y-196481D01*
X432593Y-194730D01*
X431501Y-193272D01*
X429536Y-192397D01*
X427571Y-192689D01*
X425606Y-193856D01*
G01X442015Y-195314D02*
X443325Y-193564D01*
X444853Y-192689D01*
X446600Y-192397D01*
X448783Y-192980D01*
X450311Y-194439D01*
X450748Y-196188D01*
X450530Y-197939D01*
X449656Y-199397D01*
X445290Y-202314D01*
X443325Y-204355D01*
X442015Y-207273D01*
X441578Y-209897D01*
X450748D01*
G01X363046Y-164897D02*
Y-147397D01*
X368286D01*
X370033Y-148272D01*
X371343Y-150314D01*
X371780Y-152647D01*
X371343Y-154980D01*
X370251Y-156730D01*
X368286Y-157606D01*
X363046D01*
G01X389716Y-148856D02*
X388406Y-147980D01*
X386878Y-147397D01*
X385131D01*
X383166Y-148272D01*
X381638Y-149730D01*
X380546Y-151481D01*
X379673Y-154397D01*
X379454Y-157022D01*
X379891Y-159647D01*
X380546Y-161397D01*
X381856Y-163147D01*
X383385Y-164314D01*
X384913Y-164897D01*
X386441D01*
X387970Y-164314D01*
X389280Y-163439D01*
X390372Y-162273D01*
G01X404159Y-155564D02*
X405033Y-154689D01*
X405688Y-153231D01*
X406125Y-151188D01*
X405688Y-149439D01*
X404815Y-148272D01*
X403286Y-147397D01*
X397391D01*
Y-164897D01*
X404596D01*
X406125Y-163731D01*
X406998Y-161980D01*
X407435Y-159939D01*
X406998Y-157897D01*
X405688Y-156147D01*
X404159Y-155564D01*
X397391D01*
G01X413363Y-170730D02*
X426463D01*
G01X432391Y-164897D02*
Y-147397D01*
X442435Y-164897D01*
Y-147397D01*
G01X454913Y-164897D02*
X453166Y-164605D01*
X451638Y-163439D01*
X450328Y-161689D01*
X449454Y-159647D01*
X449018Y-157314D01*
Y-154980D01*
X449454Y-152647D01*
X450328Y-150605D01*
X451638Y-148856D01*
X453166Y-147689D01*
X454913Y-147397D01*
X456659Y-147689D01*
X458188Y-148856D01*
X459498Y-150605D01*
X460372Y-152647D01*
X460808Y-154980D01*
Y-157314D01*
X460372Y-159647D01*
X459498Y-161689D01*
X458188Y-163439D01*
X456659Y-164605D01*
X454913Y-164897D01*
G01X505754Y-147397D02*
X511213Y-164897D01*
X516672Y-147397D01*
G01X533080Y-164897D02*
X524346D01*
Y-147397D01*
X533080D01*
G01X529586Y-155855D02*
X524346D01*
G01X541846Y-164897D02*
Y-147397D01*
X547305D01*
X549051Y-148272D01*
X550143Y-149439D01*
X550580Y-151772D01*
X550143Y-154106D01*
X548833Y-155564D01*
X547305Y-156439D01*
X541846D01*
G01X547305D02*
X550580Y-164897D01*
G01X563713Y-165480D02*
X563276Y-165189D01*
Y-164605D01*
X563713Y-164314D01*
X564150Y-164605D01*
Y-165189D01*
X563713Y-165480D01*
G01X537463Y-209897D02*
Y-192397D01*
X534843Y-195897D01*
G01Y-209897D02*
X540083D01*
G01X630546Y-147397D02*
Y-164897D01*
X639280D01*
G01X656343D02*
Y-153231D01*
G01Y-155272D02*
X655470Y-154106D01*
X654159Y-153522D01*
X652631Y-153231D01*
X651103Y-153814D01*
X649793Y-154980D01*
X648919Y-156730D01*
X648483Y-159064D01*
X648919Y-161397D01*
X649793Y-163147D01*
X651103Y-164314D01*
X652631Y-164897D01*
X654159Y-164605D01*
X655470Y-163731D01*
X656343Y-162564D01*
G01X665328Y-170147D02*
X666638Y-170730D01*
X668385Y-170147D01*
X669476Y-168981D01*
X670350Y-167522D01*
X671659Y-162856D01*
X674498Y-153231D01*
G01X667511D02*
X671659Y-162856D01*
G01X684138Y-157022D02*
X691125D01*
X690470Y-154980D01*
X689378Y-153814D01*
X687850Y-153231D01*
X686321Y-153522D01*
X685011Y-154397D01*
X684138Y-156439D01*
X683701Y-158189D01*
Y-159939D01*
X684138Y-161689D01*
X685230Y-163439D01*
X686540Y-164605D01*
X688068Y-164897D01*
X689596Y-164314D01*
X691125Y-162564D01*
G01X701856Y-164897D02*
Y-153231D01*
G01Y-155564D02*
X702948Y-154397D01*
X704040Y-153522D01*
X705568Y-153231D01*
X706659Y-153522D01*
X707970Y-154397D01*
G01X719138Y-162856D02*
X720230Y-164022D01*
X721758Y-164897D01*
X723068D01*
X724378Y-164314D01*
X725251Y-163439D01*
X725688Y-162273D01*
X725470Y-160522D01*
X724596Y-159647D01*
X720666Y-157897D01*
X719793Y-155855D01*
X720230Y-154397D01*
X721103Y-153522D01*
X722413Y-153231D01*
X723723Y-153522D01*
X725033Y-154397D01*
G01X638860Y-209897D02*
Y-192397D01*
X643226D01*
X644973Y-193272D01*
X646283Y-194439D01*
X647375Y-196188D01*
X648248Y-198231D01*
X648466Y-201147D01*
X648248Y-204064D01*
X647375Y-206106D01*
X646283Y-207856D01*
X644973Y-209022D01*
X643226Y-209897D01*
X638860D01*
G01X656796D02*
Y-192397D01*
X662255D01*
X664001Y-193272D01*
X665093Y-194439D01*
X665530Y-196772D01*
X665093Y-199106D01*
X663783Y-200564D01*
X662255Y-201439D01*
X656796D01*
G01X662255D02*
X665530Y-209897D01*
G01X676043Y-192397D02*
X681283D01*
G01X678663D02*
Y-209897D01*
G01X676043D02*
X681283D01*
G01X691796Y-192397D02*
Y-209897D01*
X700530D01*
G01X709296Y-192397D02*
Y-209897D01*
X718030D01*
G01X781410Y-164897D02*
Y-147397D01*
X785776D01*
X787523Y-148272D01*
X788833Y-149439D01*
X789925Y-151188D01*
X790798Y-153231D01*
X791016Y-156147D01*
X790798Y-159064D01*
X789925Y-161106D01*
X788833Y-162856D01*
X787523Y-164022D01*
X785776Y-164897D01*
X781410D01*
G01X800438Y-157022D02*
X807425D01*
X806770Y-154980D01*
X805678Y-153814D01*
X804150Y-153231D01*
X802621Y-153522D01*
X801311Y-154397D01*
X800438Y-156439D01*
X800001Y-158189D01*
Y-159939D01*
X800438Y-161689D01*
X801530Y-163439D01*
X802840Y-164605D01*
X804368Y-164897D01*
X805896Y-164314D01*
X807425Y-162564D01*
G01X817938Y-162856D02*
X819030Y-164022D01*
X820558Y-164897D01*
X821868D01*
X823178Y-164314D01*
X824051Y-163439D01*
X824488Y-162273D01*
X824270Y-160522D01*
X823396Y-159647D01*
X819466Y-157897D01*
X818593Y-155855D01*
X819030Y-154397D01*
X819903Y-153522D01*
X821213Y-153231D01*
X822523Y-153522D01*
X823833Y-154397D01*
G01X838713Y-153231D02*
Y-164897D01*
G01Y-148564D02*
X838276Y-148272D01*
Y-147689D01*
X838713Y-147397D01*
X839150Y-147689D01*
Y-148272D01*
X838713Y-148564D01*
G01X853156Y-169272D02*
X854685Y-170439D01*
X856431Y-170730D01*
X857959Y-170439D01*
X859270Y-168981D01*
X860143Y-166939D01*
Y-153231D01*
G01Y-155564D02*
X859270Y-154397D01*
X857959Y-153522D01*
X856431Y-153231D01*
X854685Y-153814D01*
X853593Y-154980D01*
X852719Y-157022D01*
X852283Y-159064D01*
X852501Y-160814D01*
X853375Y-162856D01*
X854685Y-164314D01*
X856431Y-164897D01*
X857741Y-164605D01*
X859270Y-163439D01*
X860143Y-162273D01*
G01X870001Y-164897D02*
Y-153231D01*
G01Y-156147D02*
X870875Y-154689D01*
X872185Y-153522D01*
X873931Y-153231D01*
X875459Y-153522D01*
X876770Y-154689D01*
X877425Y-156730D01*
Y-164897D01*
G01X887938Y-157022D02*
X894925D01*
X894270Y-154980D01*
X893178Y-153814D01*
X891650Y-153231D01*
X890121Y-153522D01*
X888811Y-154397D01*
X887938Y-156439D01*
X887501Y-158189D01*
Y-159939D01*
X887938Y-161689D01*
X889030Y-163439D01*
X890340Y-164605D01*
X891868Y-164897D01*
X893396Y-164314D01*
X894925Y-162564D01*
G01X905656Y-164897D02*
Y-153231D01*
G01Y-155564D02*
X906748Y-154397D01*
X907840Y-153522D01*
X909368Y-153231D01*
X910459Y-153522D01*
X911770Y-154397D01*
G01X825596Y-209897D02*
Y-192397D01*
X831055D01*
X832801Y-193272D01*
X833893Y-194439D01*
X834330Y-196772D01*
X833893Y-199106D01*
X832583Y-200564D01*
X831055Y-201439D01*
X825596D01*
G01X831055D02*
X834330Y-209897D01*
G01X847463D02*
X846153Y-209605D01*
X844843Y-208439D01*
X843969Y-206397D01*
X843533Y-204064D01*
X843969Y-201730D01*
X844843Y-199689D01*
X846153Y-198522D01*
X847463Y-198231D01*
X848773Y-198522D01*
X850083Y-199689D01*
X850956Y-201730D01*
X851175Y-204064D01*
X850956Y-206397D01*
X850083Y-208439D01*
X848773Y-209605D01*
X847463Y-209897D01*
G01X861033D02*
Y-192397D01*
G01Y-201147D02*
X862125Y-199397D01*
X863435Y-198522D01*
X864745Y-198231D01*
X866709Y-198814D01*
X868020Y-199980D01*
X868893Y-202022D01*
Y-204355D01*
X868456Y-206689D01*
X867583Y-208439D01*
X866055Y-209605D01*
X864745Y-209897D01*
X863435Y-209605D01*
X862125Y-208731D01*
X861033Y-207273D01*
G01X897819Y178203D02*
X893519D01*
G02Y181403I0J1600D01*
G01X897819D01*
G02Y178203I0J-1600D01*
G01X897349Y186408D02*
X895849Y181408D01*
X894349Y186408D01*
X897349D01*
G01X895849Y181408D02*
Y189835D01*
G01X895796Y351431D02*
Y343004D01*
G01X897296Y346431D02*
X895796Y351431D01*
X894296Y346431D01*
X897296D01*
G01X897819Y351431D02*
X893519D01*
G02Y354631I0J1600D01*
G01X897819D01*
G02Y351431I0J-1600D01*
G01X897349Y591920D02*
X895849Y586920D01*
X894349Y591920D01*
X897349D01*
G01X895849Y586920D02*
Y595347D01*
G01X897819Y583715D02*
X893519D01*
G02Y586915I0J1600D01*
G01X897819D01*
G02Y583715I0J-1600D01*
G01X895796Y756943D02*
Y748516D01*
G01X897296Y751943D02*
X895796Y756943D01*
X894296Y751943D01*
X897296D01*
G01X897819Y756943D02*
X893519D01*
G02Y760143I0J1600D01*
G01X897819D01*
G02Y756943I0J-1600D01*
G01X897349Y997432D02*
X895849Y992432D01*
X894349Y997432D01*
X897349D01*
G01X895849Y992432D02*
Y1000859D01*
G01X897819Y989227D02*
X893519D01*
G02Y992427I0J1600D01*
G01X897819D01*
G02Y989227I0J-1600D01*
G01X895796Y1162455D02*
Y1154028D01*
G01X897296Y1157455D02*
X895796Y1162455D01*
X894296Y1157455D01*
X897296D01*
G01X897819Y1162455D02*
X893519D01*
G02Y1165655I0J1600D01*
G01X897819D01*
G02Y1162455I0J-1600D01*
G01X897349Y1402944D02*
X895849Y1397944D01*
X894349Y1402944D01*
X897349D01*
G01X895849Y1397944D02*
Y1406371D01*
G01X897819Y1394739D02*
X893519D01*
G02Y1397939I0J1600D01*
G01X897819D01*
G02Y1394739I0J-1600D01*
G01X895796Y1567967D02*
Y1559540D01*
G01X897296Y1562967D02*
X895796Y1567967D01*
X894296Y1562967D01*
X897296D01*
G01X897819Y1567967D02*
X893519D01*
G02Y1571167I0J1600D01*
G01X897819D01*
G02Y1567967I0J-1600D01*
G01X897349Y1808456D02*
X895849Y1803456D01*
X894349Y1808456D01*
X897349D01*
G01X895849Y1803456D02*
Y1811883D01*
G01X897819Y1800251D02*
X893519D01*
G02Y1803451I0J1600D01*
G01X897819D01*
G02Y1800251I0J-1600D01*
G01X895796Y1973479D02*
Y1965052D01*
G01X897296Y1968479D02*
X895796Y1973479D01*
X894296Y1968479D01*
X897296D01*
G01X897819Y1973479D02*
X893519D01*
G02Y1976679I0J1600D01*
G01X897819D01*
G02Y1973479I0J-1600D01*
G01X952413Y-209897D02*
Y-192397D01*
X949793Y-195897D01*
G01Y-209897D02*
X955033D01*
G01X969913Y-192397D02*
X968166Y-192980D01*
X966856Y-194439D01*
X965983Y-196188D01*
X965328Y-198522D01*
X965110Y-201147D01*
X965328Y-203772D01*
X965983Y-206106D01*
X966856Y-207856D01*
X968166Y-209314D01*
X969913Y-209897D01*
X971659Y-209314D01*
X972970Y-207856D01*
X973843Y-206106D01*
X974498Y-203772D01*
X974716Y-201147D01*
X974498Y-198522D01*
X973843Y-196188D01*
X972970Y-194439D01*
X971659Y-192980D01*
X969913Y-192397D01*
G01X983483Y-210480D02*
X991343Y-192397D01*
G01X1004913Y-209897D02*
Y-192397D01*
X1002293Y-195897D01*
G01Y-209897D02*
X1007533D01*
G01X1018265Y-202606D02*
X1019793Y-200564D01*
X1021103Y-199397D01*
X1022850Y-198814D01*
X1024378Y-199397D01*
X1025470Y-200564D01*
X1026343Y-202314D01*
X1026561Y-204355D01*
X1026343Y-206106D01*
X1025470Y-207856D01*
X1024159Y-209314D01*
X1022631Y-209897D01*
X1020885Y-209314D01*
X1019356Y-207564D01*
X1018483Y-204939D01*
X1018265Y-202022D01*
X1018701Y-198231D01*
X1019356Y-196188D01*
X1020448Y-194147D01*
X1021976Y-192689D01*
X1023505Y-192397D01*
X1025033Y-192980D01*
X1026125Y-194439D01*
G01X1035983Y-210480D02*
X1043843Y-192397D01*
G01X1053265Y-195314D02*
X1054575Y-193564D01*
X1056103Y-192689D01*
X1057850Y-192397D01*
X1060033Y-192980D01*
X1061561Y-194439D01*
X1061998Y-196188D01*
X1061780Y-197939D01*
X1060906Y-199397D01*
X1056540Y-202314D01*
X1054575Y-204355D01*
X1053265Y-207273D01*
X1052828Y-209897D01*
X1061998D01*
G01X1074913Y-192397D02*
X1073166Y-192980D01*
X1071856Y-194439D01*
X1070983Y-196188D01*
X1070328Y-198522D01*
X1070110Y-201147D01*
X1070328Y-203772D01*
X1070983Y-206106D01*
X1071856Y-207856D01*
X1073166Y-209314D01*
X1074913Y-209897D01*
X1076659Y-209314D01*
X1077970Y-207856D01*
X1078843Y-206106D01*
X1079498Y-203772D01*
X1079716Y-201147D01*
X1079498Y-198522D01*
X1078843Y-196188D01*
X1077970Y-194439D01*
X1076659Y-192980D01*
X1074913Y-192397D01*
G01X1092413Y-209897D02*
Y-192397D01*
X1089793Y-195897D01*
G01Y-209897D02*
X1095033D01*
G01X1105765Y-195314D02*
X1107075Y-193564D01*
X1108603Y-192689D01*
X1110350Y-192397D01*
X1112533Y-192980D01*
X1114061Y-194439D01*
X1114498Y-196188D01*
X1114280Y-197939D01*
X1113406Y-199397D01*
X1109040Y-202314D01*
X1107075Y-204355D01*
X1105765Y-207273D01*
X1105328Y-209897D01*
X1114498D01*
G01X1000110Y-164897D02*
Y-147397D01*
X1004476D01*
X1006223Y-148272D01*
X1007533Y-149439D01*
X1008625Y-151188D01*
X1009498Y-153231D01*
X1009716Y-156147D01*
X1009498Y-159064D01*
X1008625Y-161106D01*
X1007533Y-162856D01*
X1006223Y-164022D01*
X1004476Y-164897D01*
X1000110D01*
G01X1026343D02*
Y-153231D01*
G01Y-155272D02*
X1025470Y-154106D01*
X1024159Y-153522D01*
X1022631Y-153231D01*
X1021103Y-153814D01*
X1019793Y-154980D01*
X1018919Y-156730D01*
X1018483Y-159064D01*
X1018919Y-161397D01*
X1019793Y-163147D01*
X1021103Y-164314D01*
X1022631Y-164897D01*
X1024159Y-164605D01*
X1025470Y-163731D01*
X1026343Y-162564D01*
G01X1039913Y-147397D02*
Y-164897D01*
G01X1036856Y-153231D02*
X1042970D01*
G01X1054138Y-157022D02*
X1061125D01*
X1060470Y-154980D01*
X1059378Y-153814D01*
X1057850Y-153231D01*
X1056321Y-153522D01*
X1055011Y-154397D01*
X1054138Y-156439D01*
X1053701Y-158189D01*
Y-159939D01*
X1054138Y-161689D01*
X1055230Y-163439D01*
X1056540Y-164605D01*
X1058068Y-164897D01*
X1059596Y-164314D01*
X1061125Y-162564D01*
G01X1190385Y1445200D02*
Y1457700D01*
X1197515Y1445200D01*
Y1457700D01*
G01X1206350Y1445200D02*
X1205420Y1445408D01*
X1204490Y1446241D01*
X1203870Y1447700D01*
X1203560Y1449367D01*
X1203870Y1451033D01*
X1204490Y1452492D01*
X1205420Y1453325D01*
X1206350Y1453533D01*
X1207280Y1453325D01*
X1208210Y1452492D01*
X1208830Y1451033D01*
X1208985Y1449367D01*
X1208830Y1447700D01*
X1208210Y1446241D01*
X1207280Y1445408D01*
X1206350Y1445200D01*
G01X1218750Y1457700D02*
Y1445200D01*
G01X1216580Y1453533D02*
X1220920D01*
G01X1228825Y1450825D02*
X1233785D01*
X1233320Y1452283D01*
X1232545Y1453117D01*
X1231460Y1453533D01*
X1230375Y1453325D01*
X1229445Y1452700D01*
X1228825Y1451242D01*
X1228515Y1449991D01*
Y1448742D01*
X1228825Y1447492D01*
X1229600Y1446241D01*
X1230530Y1445408D01*
X1231615Y1445200D01*
X1232700Y1445617D01*
X1233785Y1446866D01*
G01X1243550Y1444783D02*
X1243240Y1444992D01*
Y1445408D01*
X1243550Y1445617D01*
X1243860Y1445408D01*
Y1444992D01*
X1243550Y1444783D01*
G01Y1450408D02*
X1243240Y1450617D01*
Y1451033D01*
X1243550Y1451242D01*
X1243860Y1451033D01*
Y1450617D01*
X1243550Y1450408D01*
G01X1252850Y1445200D02*
Y1457700D01*
X1256725D01*
X1257965Y1457075D01*
X1258740Y1456242D01*
X1259050Y1454575D01*
X1258740Y1452908D01*
X1257810Y1451867D01*
X1256725Y1451242D01*
X1252850D01*
G01X1256725D02*
X1259050Y1445200D01*
G01X1266025Y1450825D02*
X1270985D01*
X1270520Y1452283D01*
X1269745Y1453117D01*
X1268660Y1453533D01*
X1267575Y1453325D01*
X1266645Y1452700D01*
X1266025Y1451242D01*
X1265715Y1449991D01*
Y1448742D01*
X1266025Y1447492D01*
X1266800Y1446241D01*
X1267730Y1445408D01*
X1268815Y1445200D01*
X1269900Y1445617D01*
X1270985Y1446866D01*
G01X1279820Y1445200D02*
Y1455825D01*
X1280130Y1456866D01*
X1280750Y1457492D01*
X1281680Y1457700D01*
X1282610Y1457283D01*
X1283075Y1456242D01*
G01X1281215Y1452700D02*
X1278115D01*
G01X1290825Y1450825D02*
X1295785D01*
X1295320Y1452283D01*
X1294545Y1453117D01*
X1293460Y1453533D01*
X1292375Y1453325D01*
X1291445Y1452700D01*
X1290825Y1451242D01*
X1290515Y1449991D01*
Y1448742D01*
X1290825Y1447492D01*
X1291600Y1446241D01*
X1292530Y1445408D01*
X1293615Y1445200D01*
X1294700Y1445617D01*
X1295785Y1446866D01*
G01X1303380Y1445200D02*
Y1453533D01*
G01Y1451867D02*
X1304155Y1452700D01*
X1304930Y1453325D01*
X1306015Y1453533D01*
X1306790Y1453325D01*
X1307720Y1452700D01*
G01X1330350Y1457700D02*
Y1445200D01*
G01X1328180Y1453533D02*
X1332520D01*
G01X1342750Y1445200D02*
X1341820Y1445408D01*
X1340890Y1446241D01*
X1340270Y1447700D01*
X1339960Y1449367D01*
X1340270Y1451033D01*
X1340890Y1452492D01*
X1341820Y1453325D01*
X1342750Y1453533D01*
X1343680Y1453325D01*
X1344610Y1452492D01*
X1345230Y1451033D01*
X1345385Y1449367D01*
X1345230Y1447700D01*
X1344610Y1446241D01*
X1343680Y1445408D01*
X1342750Y1445200D01*
G01X1364140D02*
Y1457700D01*
X1367240D01*
X1368480Y1457075D01*
X1369410Y1456242D01*
X1370185Y1454992D01*
X1370805Y1453533D01*
X1370960Y1451450D01*
X1370805Y1449367D01*
X1370185Y1447908D01*
X1369410Y1446658D01*
X1368480Y1445825D01*
X1367240Y1445200D01*
X1364140D01*
G01X1376850D02*
Y1457700D01*
X1380725D01*
X1381965Y1457075D01*
X1382740Y1456242D01*
X1383050Y1454575D01*
X1382740Y1452908D01*
X1381810Y1451867D01*
X1380725Y1451242D01*
X1376850D01*
G01X1380725D02*
X1383050Y1445200D01*
G01X1390490Y1457700D02*
X1394210D01*
G01X1392350D02*
Y1445200D01*
G01X1390490D02*
X1394210D01*
G01X1401650Y1457700D02*
Y1445200D01*
X1407850D01*
G01X1414050Y1457700D02*
Y1445200D01*
X1420250D01*
G01X1441950D02*
Y1457700D01*
G01X1457140Y1445200D02*
Y1453533D01*
G01Y1452075D02*
X1456520Y1452908D01*
X1455590Y1453325D01*
X1454505Y1453533D01*
X1453420Y1453117D01*
X1452490Y1452283D01*
X1451870Y1451033D01*
X1451560Y1449367D01*
X1451870Y1447700D01*
X1452490Y1446450D01*
X1453420Y1445617D01*
X1454505Y1445200D01*
X1455590Y1445408D01*
X1456520Y1446033D01*
X1457140Y1446866D01*
G01X1463495Y1441450D02*
X1464425Y1441033D01*
X1465665Y1441450D01*
X1466440Y1442283D01*
X1467060Y1443325D01*
X1467990Y1446658D01*
X1470005Y1453533D01*
G01X1465045D02*
X1467990Y1446658D01*
G01X1476825Y1450825D02*
X1481785D01*
X1481320Y1452283D01*
X1480545Y1453117D01*
X1479460Y1453533D01*
X1478375Y1453325D01*
X1477445Y1452700D01*
X1476825Y1451242D01*
X1476515Y1449991D01*
Y1448742D01*
X1476825Y1447492D01*
X1477600Y1446241D01*
X1478530Y1445408D01*
X1479615Y1445200D01*
X1480700Y1445617D01*
X1481785Y1446866D01*
G01X1489380Y1445200D02*
Y1453533D01*
G01Y1451867D02*
X1490155Y1452700D01*
X1490930Y1453325D01*
X1492015Y1453533D01*
X1492790Y1453325D01*
X1493720Y1452700D01*
G01X1515420Y1445200D02*
Y1455825D01*
X1515730Y1456866D01*
X1516350Y1457492D01*
X1517280Y1457700D01*
X1518210Y1457283D01*
X1518675Y1456242D01*
G01X1516815Y1452700D02*
X1513715D01*
G01X1528750Y1445200D02*
X1527820Y1445408D01*
X1526890Y1446241D01*
X1526270Y1447700D01*
X1525960Y1449367D01*
X1526270Y1451033D01*
X1526890Y1452492D01*
X1527820Y1453325D01*
X1528750Y1453533D01*
X1529680Y1453325D01*
X1530610Y1452492D01*
X1531230Y1451033D01*
X1531385Y1449367D01*
X1531230Y1447700D01*
X1530610Y1446241D01*
X1529680Y1445408D01*
X1528750Y1445200D01*
G01X1538980D02*
Y1453533D01*
G01Y1451867D02*
X1539755Y1452700D01*
X1540530Y1453325D01*
X1541615Y1453533D01*
X1542390Y1453325D01*
X1543320Y1452700D01*
G01X1569050Y1445200D02*
X1562850D01*
Y1457700D01*
X1569050D01*
G01X1566570Y1451658D02*
X1562850D01*
G01X1575250Y1457700D02*
Y1445200D01*
X1581450D01*
G01X1587650Y1457700D02*
Y1445200D01*
X1593850D01*
G01X1601290Y1457700D02*
X1605010D01*
G01X1603150D02*
Y1445200D01*
G01X1601290D02*
X1605010D01*
G01X1612450D02*
Y1457700D01*
X1616170D01*
X1617410Y1457075D01*
X1618340Y1455617D01*
X1618650Y1453950D01*
X1618340Y1452283D01*
X1617565Y1451033D01*
X1616170Y1450408D01*
X1612450D01*
G01X1624695Y1446866D02*
X1625935Y1445825D01*
X1627330Y1445200D01*
X1628570D01*
X1629810Y1445825D01*
X1630740Y1446866D01*
X1631205Y1448325D01*
X1630895Y1449783D01*
X1630120Y1451033D01*
X1628725Y1451867D01*
X1626865Y1452283D01*
X1625780Y1453117D01*
X1625315Y1454575D01*
X1625625Y1456033D01*
X1626400Y1457075D01*
X1627485Y1457700D01*
X1628570D01*
X1629655Y1457283D01*
X1630585Y1456242D01*
G01X1643450Y1445200D02*
X1637250D01*
Y1457700D01*
X1643450D01*
G01X1640970Y1451658D02*
X1637250D01*
G01X1667940Y1457700D02*
Y1445200D01*
G01Y1447075D02*
X1667320Y1446033D01*
X1666390Y1445408D01*
X1665305Y1445200D01*
X1664065Y1445617D01*
X1663135Y1446658D01*
X1662515Y1447908D01*
X1662360Y1449367D01*
X1662515Y1450825D01*
X1663135Y1452075D01*
X1664065Y1453117D01*
X1665305Y1453533D01*
X1666390Y1453325D01*
X1667165Y1452908D01*
X1667940Y1452075D01*
G01X1675380Y1445200D02*
Y1453533D01*
G01Y1451867D02*
X1676155Y1452700D01*
X1676930Y1453325D01*
X1678015Y1453533D01*
X1678790Y1453325D01*
X1679720Y1452700D01*
G01X1689950Y1453533D02*
Y1445200D01*
G01Y1456866D02*
X1689640Y1457075D01*
Y1457492D01*
X1689950Y1457700D01*
X1690260Y1457492D01*
Y1457075D01*
X1689950Y1456866D01*
G01X1702350Y1445200D02*
Y1457700D01*
G01X1714750Y1445200D02*
Y1457700D01*
G01X1742340D02*
Y1445200D01*
G01Y1447075D02*
X1741720Y1446033D01*
X1740790Y1445408D01*
X1739705Y1445200D01*
X1738465Y1445617D01*
X1737535Y1446658D01*
X1736915Y1447908D01*
X1736760Y1449367D01*
X1736915Y1450825D01*
X1737535Y1452075D01*
X1738465Y1453117D01*
X1739705Y1453533D01*
X1740790Y1453325D01*
X1741565Y1452908D01*
X1742340Y1452075D01*
G01X1751950Y1453533D02*
Y1445200D01*
G01Y1456866D02*
X1751640Y1457075D01*
Y1457492D01*
X1751950Y1457700D01*
X1752260Y1457492D01*
Y1457075D01*
X1751950Y1456866D01*
G01X1762180Y1445200D02*
Y1453533D01*
G01Y1451867D02*
X1762955Y1452700D01*
X1763730Y1453325D01*
X1764815Y1453533D01*
X1765590Y1453325D01*
X1766520Y1452700D01*
G01X1774425Y1450825D02*
X1779385D01*
X1778920Y1452283D01*
X1778145Y1453117D01*
X1777060Y1453533D01*
X1775975Y1453325D01*
X1775045Y1452700D01*
X1774425Y1451242D01*
X1774115Y1449991D01*
Y1448742D01*
X1774425Y1447492D01*
X1775200Y1446241D01*
X1776130Y1445408D01*
X1777215Y1445200D01*
X1778300Y1445617D01*
X1779385Y1446866D01*
G01X1791630Y1452492D02*
X1790545Y1453325D01*
X1789615Y1453533D01*
X1788375Y1453117D01*
X1787445Y1452283D01*
X1786825Y1450825D01*
X1786670Y1449367D01*
X1786825Y1447908D01*
X1787445Y1446658D01*
X1788375Y1445617D01*
X1789615Y1445200D01*
X1790700Y1445617D01*
X1791630Y1446450D01*
G01X1801550Y1457700D02*
Y1445200D01*
G01X1799380Y1453533D02*
X1803720D01*
G01X1813950D02*
Y1445200D01*
G01Y1456866D02*
X1813640Y1457075D01*
Y1457492D01*
X1813950Y1457700D01*
X1814260Y1457492D01*
Y1457075D01*
X1813950Y1456866D01*
G01X1826350Y1445200D02*
X1825420Y1445408D01*
X1824490Y1446241D01*
X1823870Y1447700D01*
X1823560Y1449367D01*
X1823870Y1451033D01*
X1824490Y1452492D01*
X1825420Y1453325D01*
X1826350Y1453533D01*
X1827280Y1453325D01*
X1828210Y1452492D01*
X1828830Y1451033D01*
X1828985Y1449367D01*
X1828830Y1447700D01*
X1828210Y1446241D01*
X1827280Y1445408D01*
X1826350Y1445200D01*
G01X1836115D02*
Y1453533D01*
G01Y1451450D02*
X1836735Y1452492D01*
X1837665Y1453325D01*
X1838905Y1453533D01*
X1839990Y1453325D01*
X1840920Y1452492D01*
X1841385Y1451033D01*
Y1445200D01*
G01X1189300Y1475200D02*
Y1809300D01*
X1672900D01*
Y1475200D01*
X1189300D01*
G01Y1503300D02*
X1672900D01*
G01X1189300Y1531400D02*
X1672900D01*
G01X1189300Y1559500D02*
X1672900D01*
G01X1189300Y1587600D02*
X1672900D01*
G01X1189300Y1615700D02*
X1672900D01*
G01X1189300Y1643800D02*
X1672900D01*
G01X1189300Y1671900D02*
X1672900D01*
G01X1189300Y1700000D02*
X1672900D01*
G01X1200305Y1737450D02*
Y1749950D01*
X1206195D01*
G01X1204025Y1743908D02*
X1200305D01*
G01X1213790Y1749950D02*
X1217510D01*
G01X1215650D02*
Y1737450D01*
G01X1213790D02*
X1217510D01*
G01X1228980Y1743700D02*
X1232080D01*
Y1739950D01*
X1231150Y1738700D01*
X1230065Y1737867D01*
X1228515Y1737450D01*
X1226965Y1737867D01*
X1225880Y1738700D01*
X1224950Y1739950D01*
X1224330Y1741408D01*
X1224020Y1743075D01*
Y1744533D01*
X1224330Y1745783D01*
X1224950Y1747242D01*
X1225880Y1748492D01*
X1226810Y1749325D01*
X1228050Y1749950D01*
X1229135D01*
X1230375Y1749533D01*
X1231305Y1748700D01*
G01X1237040Y1749950D02*
Y1740992D01*
X1237660Y1739116D01*
X1238900Y1737867D01*
X1240450Y1737450D01*
X1242000Y1737867D01*
X1243240Y1739116D01*
X1243860Y1740992D01*
Y1749950D01*
G01X1249750Y1737450D02*
Y1749950D01*
X1253625D01*
X1254865Y1749325D01*
X1255640Y1748492D01*
X1255950Y1746825D01*
X1255640Y1745158D01*
X1254710Y1744117D01*
X1253625Y1743492D01*
X1249750D01*
G01X1253625D02*
X1255950Y1737450D01*
G01X1268350D02*
X1262150D01*
Y1749950D01*
X1268350D01*
G01X1265870Y1743908D02*
X1262150D01*
G01X1189300Y1728100D02*
X1672900D01*
G01X1189300Y1756200D02*
X1672900D01*
G01X1189300Y1784300D02*
X1672900D01*
G01X1279200Y1756200D02*
Y1475200D01*
G01X1272690Y1790550D02*
Y1803050D01*
X1275790D01*
X1277030Y1802425D01*
X1277960Y1801592D01*
X1278735Y1800342D01*
X1279355Y1798883D01*
X1279510Y1796800D01*
X1279355Y1794717D01*
X1278735Y1793258D01*
X1277960Y1792008D01*
X1277030Y1791175D01*
X1275790Y1790550D01*
X1272690D01*
G01X1285400D02*
Y1803050D01*
X1289275D01*
X1290515Y1802425D01*
X1291290Y1801592D01*
X1291600Y1799925D01*
X1291290Y1798258D01*
X1290360Y1797217D01*
X1289275Y1796592D01*
X1285400D01*
G01X1289275D02*
X1291600Y1790550D01*
G01X1299040Y1803050D02*
X1302760D01*
G01X1300900D02*
Y1790550D01*
G01X1299040D02*
X1302760D01*
G01X1310200Y1803050D02*
Y1790550D01*
X1316400D01*
G01X1322600Y1803050D02*
Y1790550D01*
X1328800D01*
G01X1353910Y1802008D02*
X1352980Y1802633D01*
X1351895Y1803050D01*
X1350655D01*
X1349260Y1802425D01*
X1348175Y1801383D01*
X1347400Y1800133D01*
X1346780Y1798050D01*
X1346625Y1796175D01*
X1346935Y1794300D01*
X1347400Y1793050D01*
X1348330Y1791800D01*
X1349415Y1790967D01*
X1350500Y1790550D01*
X1351585D01*
X1352670Y1790967D01*
X1353600Y1791591D01*
X1354375Y1792425D01*
G01X1359645Y1790550D02*
Y1803050D01*
G01X1366155D02*
Y1790550D01*
G01Y1796800D02*
X1359645D01*
G01X1371425Y1790550D02*
X1375300Y1803050D01*
X1379175Y1790550D01*
G01X1377780Y1794925D02*
X1372820D01*
G01X1384600Y1790550D02*
Y1803050D01*
X1388475D01*
X1389715Y1802425D01*
X1390490Y1801592D01*
X1390800Y1799925D01*
X1390490Y1798258D01*
X1389560Y1797217D01*
X1388475Y1796592D01*
X1384600D01*
G01X1388475D02*
X1390800Y1790550D01*
G01X1400100Y1803050D02*
Y1790550D01*
G01X1396535Y1803050D02*
X1403665D01*
G01X1412500Y1790133D02*
X1412190Y1790342D01*
Y1790758D01*
X1412500Y1790967D01*
X1412810Y1790758D01*
Y1790342D01*
X1412500Y1790133D01*
G01Y1795758D02*
X1412190Y1795967D01*
Y1796383D01*
X1412500Y1796592D01*
X1412810Y1796383D01*
Y1795967D01*
X1412500Y1795758D01*
G01X1437300Y1803050D02*
Y1790550D01*
G01X1433735Y1803050D02*
X1440865D01*
G01X1449700Y1790550D02*
X1448460Y1790758D01*
X1447375Y1791591D01*
X1446445Y1792842D01*
X1445825Y1794300D01*
X1445515Y1795967D01*
Y1797633D01*
X1445825Y1799300D01*
X1446445Y1800758D01*
X1447375Y1802008D01*
X1448460Y1802842D01*
X1449700Y1803050D01*
X1450940Y1802842D01*
X1452025Y1802008D01*
X1452955Y1800758D01*
X1453575Y1799300D01*
X1453885Y1797633D01*
Y1795967D01*
X1453575Y1794300D01*
X1452955Y1792842D01*
X1452025Y1791591D01*
X1450940Y1790758D01*
X1449700Y1790550D01*
G01X1459000D02*
Y1803050D01*
X1462720D01*
X1463960Y1802425D01*
X1464890Y1800967D01*
X1465200Y1799300D01*
X1464890Y1797633D01*
X1464115Y1796383D01*
X1462720Y1795758D01*
X1459000D01*
G01X1486900Y1803050D02*
Y1790550D01*
G01X1484730Y1798883D02*
X1489070D01*
G01X1499300Y1790550D02*
X1498370Y1790758D01*
X1497440Y1791591D01*
X1496820Y1793050D01*
X1496510Y1794717D01*
X1496820Y1796383D01*
X1497440Y1797842D01*
X1498370Y1798675D01*
X1499300Y1798883D01*
X1500230Y1798675D01*
X1501160Y1797842D01*
X1501780Y1796383D01*
X1501935Y1794717D01*
X1501780Y1793050D01*
X1501160Y1791591D01*
X1500230Y1790758D01*
X1499300Y1790550D01*
G01X1525340Y1797217D02*
X1525960Y1797842D01*
X1526425Y1798883D01*
X1526735Y1800342D01*
X1526425Y1801592D01*
X1525805Y1802425D01*
X1524720Y1803050D01*
X1520535D01*
Y1790550D01*
X1525650D01*
X1526735Y1791383D01*
X1527355Y1792633D01*
X1527665Y1794092D01*
X1527355Y1795550D01*
X1526425Y1796800D01*
X1525340Y1797217D01*
X1520535D01*
G01X1536500Y1790550D02*
X1535260Y1790758D01*
X1534175Y1791591D01*
X1533245Y1792842D01*
X1532625Y1794300D01*
X1532315Y1795967D01*
Y1797633D01*
X1532625Y1799300D01*
X1533245Y1800758D01*
X1534175Y1802008D01*
X1535260Y1802842D01*
X1536500Y1803050D01*
X1537740Y1802842D01*
X1538825Y1802008D01*
X1539755Y1800758D01*
X1540375Y1799300D01*
X1540685Y1797633D01*
Y1795967D01*
X1540375Y1794300D01*
X1539755Y1792842D01*
X1538825Y1791591D01*
X1537740Y1790758D01*
X1536500Y1790550D01*
G01X1548900Y1803050D02*
Y1790550D01*
G01X1545335Y1803050D02*
X1552465D01*
G01X1561300D02*
Y1790550D01*
G01X1557735Y1803050D02*
X1564865D01*
G01X1573700Y1790550D02*
X1572460Y1790758D01*
X1571375Y1791591D01*
X1570445Y1792842D01*
X1569825Y1794300D01*
X1569515Y1795967D01*
Y1797633D01*
X1569825Y1799300D01*
X1570445Y1800758D01*
X1571375Y1802008D01*
X1572460Y1802842D01*
X1573700Y1803050D01*
X1574940Y1802842D01*
X1576025Y1802008D01*
X1576955Y1800758D01*
X1577575Y1799300D01*
X1577885Y1797633D01*
Y1795967D01*
X1577575Y1794300D01*
X1576955Y1792842D01*
X1576025Y1791591D01*
X1574940Y1790758D01*
X1573700Y1790550D01*
G01X1582070D02*
Y1803050D01*
X1586100Y1792633D01*
X1590130Y1803050D01*
Y1790550D01*
G01X1303225Y1765550D02*
X1307100Y1778050D01*
X1310975Y1765550D01*
G01X1309580Y1769925D02*
X1304620D01*
G01X1316400Y1778050D02*
Y1765550D01*
X1322600D01*
G01X1328800Y1778050D02*
Y1765550D01*
X1335000D01*
G01X1353290Y1778050D02*
Y1769092D01*
X1353910Y1767216D01*
X1355150Y1765967D01*
X1356700Y1765550D01*
X1358250Y1765967D01*
X1359490Y1767216D01*
X1360110Y1769092D01*
Y1778050D01*
G01X1365535Y1765550D02*
Y1778050D01*
X1372665Y1765550D01*
Y1778050D01*
G01X1379640D02*
X1383360D01*
G01X1381500D02*
Y1765550D01*
G01X1379640D02*
X1383360D01*
G01X1393900Y1778050D02*
Y1765550D01*
G01X1390335Y1778050D02*
X1397465D01*
G01X1403045Y1767216D02*
X1404285Y1766175D01*
X1405680Y1765550D01*
X1406920D01*
X1408160Y1766175D01*
X1409090Y1767216D01*
X1409555Y1768675D01*
X1409245Y1770133D01*
X1408470Y1771383D01*
X1407075Y1772217D01*
X1405215Y1772633D01*
X1404130Y1773467D01*
X1403665Y1774925D01*
X1403975Y1776383D01*
X1404750Y1777425D01*
X1405835Y1778050D01*
X1406920D01*
X1408005Y1777633D01*
X1408935Y1776592D01*
G01X1427225Y1765550D02*
X1431100Y1778050D01*
X1434975Y1765550D01*
G01X1433580Y1769925D02*
X1428620D01*
G01X1440400Y1765550D02*
Y1778050D01*
X1444275D01*
X1445515Y1777425D01*
X1446290Y1776592D01*
X1446600Y1774925D01*
X1446290Y1773258D01*
X1445360Y1772217D01*
X1444275Y1771592D01*
X1440400D01*
G01X1444275D02*
X1446600Y1765550D01*
G01X1459000D02*
X1452800D01*
Y1778050D01*
X1459000D01*
G01X1456520Y1772008D02*
X1452800D01*
G01X1478840Y1778050D02*
X1482560D01*
G01X1480700D02*
Y1765550D01*
G01X1478840D02*
X1482560D01*
G01X1489535D02*
Y1778050D01*
X1496665Y1765550D01*
Y1778050D01*
G01X1513870Y1765550D02*
Y1778050D01*
X1517900Y1767633D01*
X1521930Y1778050D01*
Y1765550D01*
G01X1528440Y1778050D02*
X1532160D01*
G01X1530300D02*
Y1765550D01*
G01X1528440D02*
X1532160D01*
G01X1539600Y1778050D02*
Y1765550D01*
X1545800D01*
G01X1551845Y1767216D02*
X1553085Y1766175D01*
X1554480Y1765550D01*
X1555720D01*
X1556960Y1766175D01*
X1557890Y1767216D01*
X1558355Y1768675D01*
X1558045Y1770133D01*
X1557270Y1771383D01*
X1555875Y1772217D01*
X1554015Y1772633D01*
X1552930Y1773467D01*
X1552465Y1774925D01*
X1552775Y1776383D01*
X1553550Y1777425D01*
X1554635Y1778050D01*
X1555720D01*
X1556805Y1777633D01*
X1557735Y1776592D01*
G01X1323840Y1483000D02*
X1324150Y1485708D01*
X1324615Y1488000D01*
X1325235Y1490083D01*
X1326010Y1492375D01*
X1327250Y1495500D01*
X1321050D01*
G01X1333140Y1484875D02*
X1334070Y1483833D01*
X1335155Y1483208D01*
X1336550Y1483000D01*
X1337945Y1483417D01*
X1339030Y1484250D01*
X1339805Y1485708D01*
X1339960Y1487375D01*
X1339650Y1489042D01*
X1338875Y1490083D01*
X1337790Y1490917D01*
X1336705Y1491125D01*
X1335620Y1490917D01*
X1334225Y1490083D01*
X1334690Y1495500D01*
X1338875D01*
G01X1348950Y1482583D02*
X1348640Y1482792D01*
Y1483208D01*
X1348950Y1483417D01*
X1349260Y1483208D01*
Y1482792D01*
X1348950Y1482583D01*
G01X1361350Y1495500D02*
X1360110Y1495083D01*
X1359180Y1494042D01*
X1358560Y1492792D01*
X1358095Y1491125D01*
X1357940Y1489250D01*
X1358095Y1487375D01*
X1358560Y1485708D01*
X1359180Y1484458D01*
X1360110Y1483417D01*
X1361350Y1483000D01*
X1362590Y1483417D01*
X1363520Y1484458D01*
X1364140Y1485708D01*
X1364605Y1487375D01*
X1364760Y1489250D01*
X1364605Y1491125D01*
X1364140Y1492792D01*
X1363520Y1494042D01*
X1362590Y1495083D01*
X1361350Y1495500D01*
G01X1371425Y1491333D02*
X1376075Y1483000D01*
G01Y1491333D02*
X1371425Y1483000D01*
G01X1382740Y1485500D02*
X1383670Y1484041D01*
X1384910Y1483208D01*
X1386305Y1483000D01*
X1387545Y1483208D01*
X1388785Y1484250D01*
X1389560Y1485500D01*
X1389715Y1486750D01*
X1389405Y1488208D01*
X1388320Y1489250D01*
X1387235Y1489667D01*
X1385840D01*
G01X1387235D02*
X1388165Y1490292D01*
X1388940Y1491333D01*
X1389250Y1492583D01*
X1388940Y1493833D01*
X1388165Y1494875D01*
X1386770Y1495500D01*
X1385375Y1495292D01*
X1383980Y1494458D01*
G01X1395605Y1493417D02*
X1396535Y1494666D01*
X1397620Y1495292D01*
X1398860Y1495500D01*
X1400410Y1495083D01*
X1401495Y1494042D01*
X1401805Y1492792D01*
X1401650Y1491541D01*
X1401030Y1490500D01*
X1397930Y1488417D01*
X1396535Y1486958D01*
X1395605Y1484875D01*
X1395295Y1483000D01*
X1401805D01*
G01X1410950Y1482583D02*
X1410640Y1482792D01*
Y1483208D01*
X1410950Y1483417D01*
X1411260Y1483208D01*
Y1482792D01*
X1410950Y1482583D01*
G01X1423350Y1495500D02*
X1422110Y1495083D01*
X1421180Y1494042D01*
X1420560Y1492792D01*
X1420095Y1491125D01*
X1419940Y1489250D01*
X1420095Y1487375D01*
X1420560Y1485708D01*
X1421180Y1484458D01*
X1422110Y1483417D01*
X1423350Y1483000D01*
X1424590Y1483417D01*
X1425520Y1484458D01*
X1426140Y1485708D01*
X1426605Y1487375D01*
X1426760Y1489250D01*
X1426605Y1491125D01*
X1426140Y1492792D01*
X1425520Y1494042D01*
X1424590Y1495083D01*
X1423350Y1495500D01*
G01X1348950Y1511100D02*
Y1523600D01*
X1347090Y1521100D01*
G01Y1511100D02*
X1350810D01*
G01X1363210D02*
Y1523600D01*
X1357475Y1514642D01*
X1365225D01*
G01X1370805Y1516308D02*
X1371890Y1517767D01*
X1372820Y1518600D01*
X1374060Y1519017D01*
X1375145Y1518600D01*
X1375920Y1517767D01*
X1376540Y1516517D01*
X1376695Y1515058D01*
X1376540Y1513808D01*
X1375920Y1512558D01*
X1374990Y1511517D01*
X1373905Y1511100D01*
X1372665Y1511517D01*
X1371580Y1512766D01*
X1370960Y1514642D01*
X1370805Y1516725D01*
X1371115Y1519433D01*
X1371580Y1520892D01*
X1372355Y1522350D01*
X1373440Y1523392D01*
X1374525Y1523600D01*
X1375610Y1523183D01*
X1376385Y1522142D01*
G01X1386150Y1510683D02*
X1385840Y1510892D01*
Y1511308D01*
X1386150Y1511517D01*
X1386460Y1511308D01*
Y1510892D01*
X1386150Y1510683D01*
G01X1398550Y1523600D02*
X1397310Y1523183D01*
X1396380Y1522142D01*
X1395760Y1520892D01*
X1395295Y1519225D01*
X1395140Y1517350D01*
X1395295Y1515475D01*
X1395760Y1513808D01*
X1396380Y1512558D01*
X1397310Y1511517D01*
X1398550Y1511100D01*
X1399790Y1511517D01*
X1400720Y1512558D01*
X1401340Y1513808D01*
X1401805Y1515475D01*
X1401960Y1517350D01*
X1401805Y1519225D01*
X1401340Y1520892D01*
X1400720Y1522142D01*
X1399790Y1523183D01*
X1398550Y1523600D01*
G01X1352515Y1540658D02*
X1353600Y1539617D01*
X1354840Y1539200D01*
X1356080Y1539617D01*
X1357165Y1540866D01*
X1357940Y1542742D01*
X1358250Y1544617D01*
Y1546908D01*
X1357940Y1548783D01*
X1357165Y1550450D01*
X1356235Y1551283D01*
X1355150Y1551700D01*
X1353910Y1551283D01*
X1352980Y1550450D01*
X1352360Y1549200D01*
X1352050Y1547533D01*
X1352360Y1546075D01*
X1353135Y1544617D01*
X1354065Y1543783D01*
X1355150Y1543575D01*
X1356390Y1543991D01*
X1357320Y1545033D01*
X1358250Y1546908D01*
G01X1367550Y1539200D02*
Y1551700D01*
X1365690Y1549200D01*
G01Y1539200D02*
X1369410D01*
G01X1379950Y1538783D02*
X1379640Y1538992D01*
Y1539408D01*
X1379950Y1539617D01*
X1380260Y1539408D01*
Y1538992D01*
X1379950Y1538783D01*
G01X1392350Y1551700D02*
X1391110Y1551283D01*
X1390180Y1550242D01*
X1389560Y1548992D01*
X1389095Y1547325D01*
X1388940Y1545450D01*
X1389095Y1543575D01*
X1389560Y1541908D01*
X1390180Y1540658D01*
X1391110Y1539617D01*
X1392350Y1539200D01*
X1393590Y1539617D01*
X1394520Y1540658D01*
X1395140Y1541908D01*
X1395605Y1543575D01*
X1395760Y1545450D01*
X1395605Y1547325D01*
X1395140Y1548992D01*
X1394520Y1550242D01*
X1393590Y1551283D01*
X1392350Y1551700D01*
G01X1355150Y1567300D02*
X1356235Y1567508D01*
X1357475Y1568133D01*
X1358250Y1569175D01*
X1358560Y1570633D01*
X1358250Y1572091D01*
X1357320Y1573342D01*
X1355925Y1573967D01*
X1354375D01*
X1353445Y1574383D01*
X1352670Y1575425D01*
X1352360Y1576883D01*
X1352825Y1578342D01*
X1353910Y1579383D01*
X1355150Y1579800D01*
X1356390Y1579383D01*
X1357475Y1578342D01*
X1357940Y1576883D01*
X1357630Y1575425D01*
X1356855Y1574383D01*
X1355925Y1573967D01*
X1354375D01*
X1352980Y1573342D01*
X1352050Y1572091D01*
X1351740Y1570633D01*
X1352050Y1569175D01*
X1352825Y1568133D01*
X1354065Y1567508D01*
X1355150Y1567300D01*
G01X1364605Y1572508D02*
X1365690Y1573967D01*
X1366620Y1574800D01*
X1367860Y1575217D01*
X1368945Y1574800D01*
X1369720Y1573967D01*
X1370340Y1572717D01*
X1370495Y1571258D01*
X1370340Y1570008D01*
X1369720Y1568758D01*
X1368790Y1567717D01*
X1367705Y1567300D01*
X1366465Y1567717D01*
X1365380Y1568966D01*
X1364760Y1570842D01*
X1364605Y1572925D01*
X1364915Y1575633D01*
X1365380Y1577092D01*
X1366155Y1578550D01*
X1367240Y1579592D01*
X1368325Y1579800D01*
X1369410Y1579383D01*
X1370185Y1578342D01*
G01X1379950Y1566883D02*
X1379640Y1567092D01*
Y1567508D01*
X1379950Y1567717D01*
X1380260Y1567508D01*
Y1567092D01*
X1379950Y1566883D01*
G01X1392350Y1579800D02*
X1391110Y1579383D01*
X1390180Y1578342D01*
X1389560Y1577092D01*
X1389095Y1575425D01*
X1388940Y1573550D01*
X1389095Y1571675D01*
X1389560Y1570008D01*
X1390180Y1568758D01*
X1391110Y1567717D01*
X1392350Y1567300D01*
X1393590Y1567717D01*
X1394520Y1568758D01*
X1395140Y1570008D01*
X1395605Y1571675D01*
X1395760Y1573550D01*
X1395605Y1575425D01*
X1395140Y1577092D01*
X1394520Y1578342D01*
X1393590Y1579383D01*
X1392350Y1579800D01*
G01X1354840Y1595400D02*
X1355150Y1598108D01*
X1355615Y1600400D01*
X1356235Y1602483D01*
X1357010Y1604775D01*
X1358250Y1607900D01*
X1352050D01*
G01X1364140Y1597900D02*
X1365070Y1596441D01*
X1366310Y1595608D01*
X1367705Y1595400D01*
X1368945Y1595608D01*
X1370185Y1596650D01*
X1370960Y1597900D01*
X1371115Y1599150D01*
X1370805Y1600608D01*
X1369720Y1601650D01*
X1368635Y1602067D01*
X1367240D01*
G01X1368635D02*
X1369565Y1602692D01*
X1370340Y1603733D01*
X1370650Y1604983D01*
X1370340Y1606233D01*
X1369565Y1607275D01*
X1368170Y1607900D01*
X1366775Y1607692D01*
X1365380Y1606858D01*
G01X1379950Y1594983D02*
X1379640Y1595192D01*
Y1595608D01*
X1379950Y1595817D01*
X1380260Y1595608D01*
Y1595192D01*
X1379950Y1594983D01*
G01X1392350Y1607900D02*
X1391110Y1607483D01*
X1390180Y1606442D01*
X1389560Y1605192D01*
X1389095Y1603525D01*
X1388940Y1601650D01*
X1389095Y1599775D01*
X1389560Y1598108D01*
X1390180Y1596858D01*
X1391110Y1595817D01*
X1392350Y1595400D01*
X1393590Y1595817D01*
X1394520Y1596858D01*
X1395140Y1598108D01*
X1395605Y1599775D01*
X1395760Y1601650D01*
X1395605Y1603525D01*
X1395140Y1605192D01*
X1394520Y1606442D01*
X1393590Y1607483D01*
X1392350Y1607900D01*
G01X1348950Y1623500D02*
Y1636000D01*
X1347090Y1633500D01*
G01Y1623500D02*
X1350810D01*
G01X1357940Y1625375D02*
X1358870Y1624333D01*
X1359955Y1623708D01*
X1361350Y1623500D01*
X1362745Y1623917D01*
X1363830Y1624750D01*
X1364605Y1626208D01*
X1364760Y1627875D01*
X1364450Y1629542D01*
X1363675Y1630583D01*
X1362590Y1631417D01*
X1361505Y1631625D01*
X1360420Y1631417D01*
X1359025Y1630583D01*
X1359490Y1636000D01*
X1363675D01*
G01X1373440Y1623500D02*
X1373750Y1626208D01*
X1374215Y1628500D01*
X1374835Y1630583D01*
X1375610Y1632875D01*
X1376850Y1636000D01*
X1370650D01*
G01X1386150Y1623083D02*
X1385840Y1623292D01*
Y1623708D01*
X1386150Y1623917D01*
X1386460Y1623708D01*
Y1623292D01*
X1386150Y1623083D01*
G01X1398550Y1636000D02*
X1397310Y1635583D01*
X1396380Y1634542D01*
X1395760Y1633292D01*
X1395295Y1631625D01*
X1395140Y1629750D01*
X1395295Y1627875D01*
X1395760Y1626208D01*
X1396380Y1624958D01*
X1397310Y1623917D01*
X1398550Y1623500D01*
X1399790Y1623917D01*
X1400720Y1624958D01*
X1401340Y1626208D01*
X1401805Y1627875D01*
X1401960Y1629750D01*
X1401805Y1631625D01*
X1401340Y1633292D01*
X1400720Y1634542D01*
X1399790Y1635583D01*
X1398550Y1636000D01*
G01X1348950Y1651600D02*
Y1664100D01*
X1347090Y1661600D01*
G01Y1651600D02*
X1350810D01*
G01X1363210D02*
Y1664100D01*
X1357475Y1655142D01*
X1365225D01*
G01X1373750Y1664100D02*
X1372510Y1663683D01*
X1371580Y1662642D01*
X1370960Y1661392D01*
X1370495Y1659725D01*
X1370340Y1657850D01*
X1370495Y1655975D01*
X1370960Y1654308D01*
X1371580Y1653058D01*
X1372510Y1652017D01*
X1373750Y1651600D01*
X1374990Y1652017D01*
X1375920Y1653058D01*
X1376540Y1654308D01*
X1377005Y1655975D01*
X1377160Y1657850D01*
X1377005Y1659725D01*
X1376540Y1661392D01*
X1375920Y1662642D01*
X1374990Y1663683D01*
X1373750Y1664100D01*
G01X1386150Y1651183D02*
X1385840Y1651392D01*
Y1651808D01*
X1386150Y1652017D01*
X1386460Y1651808D01*
Y1651392D01*
X1386150Y1651183D01*
G01X1398550Y1664100D02*
X1397310Y1663683D01*
X1396380Y1662642D01*
X1395760Y1661392D01*
X1395295Y1659725D01*
X1395140Y1657850D01*
X1395295Y1655975D01*
X1395760Y1654308D01*
X1396380Y1653058D01*
X1397310Y1652017D01*
X1398550Y1651600D01*
X1399790Y1652017D01*
X1400720Y1653058D01*
X1401340Y1654308D01*
X1401805Y1655975D01*
X1401960Y1657850D01*
X1401805Y1659725D01*
X1401340Y1661392D01*
X1400720Y1662642D01*
X1399790Y1663683D01*
X1398550Y1664100D01*
G01X1355150Y1679700D02*
Y1692200D01*
X1353290Y1689700D01*
G01Y1679700D02*
X1357010D01*
G01X1364605Y1684908D02*
X1365690Y1686367D01*
X1366620Y1687200D01*
X1367860Y1687617D01*
X1368945Y1687200D01*
X1369720Y1686367D01*
X1370340Y1685117D01*
X1370495Y1683658D01*
X1370340Y1682408D01*
X1369720Y1681158D01*
X1368790Y1680117D01*
X1367705Y1679700D01*
X1366465Y1680117D01*
X1365380Y1681366D01*
X1364760Y1683242D01*
X1364605Y1685325D01*
X1364915Y1688033D01*
X1365380Y1689492D01*
X1366155Y1690950D01*
X1367240Y1691992D01*
X1368325Y1692200D01*
X1369410Y1691783D01*
X1370185Y1690742D01*
G01X1379950Y1679283D02*
X1379640Y1679492D01*
Y1679908D01*
X1379950Y1680117D01*
X1380260Y1679908D01*
Y1679492D01*
X1379950Y1679283D01*
G01X1392350Y1692200D02*
X1391110Y1691783D01*
X1390180Y1690742D01*
X1389560Y1689492D01*
X1389095Y1687825D01*
X1388940Y1685950D01*
X1389095Y1684075D01*
X1389560Y1682408D01*
X1390180Y1681158D01*
X1391110Y1680117D01*
X1392350Y1679700D01*
X1393590Y1680117D01*
X1394520Y1681158D01*
X1395140Y1682408D01*
X1395605Y1684075D01*
X1395760Y1685950D01*
X1395605Y1687825D01*
X1395140Y1689492D01*
X1394520Y1690742D01*
X1393590Y1691783D01*
X1392350Y1692200D01*
G01X1355150Y1707800D02*
Y1720300D01*
X1353290Y1717800D01*
G01Y1707800D02*
X1357010D01*
G01X1364605Y1718217D02*
X1365535Y1719466D01*
X1366620Y1720092D01*
X1367860Y1720300D01*
X1369410Y1719883D01*
X1370495Y1718842D01*
X1370805Y1717592D01*
X1370650Y1716341D01*
X1370030Y1715300D01*
X1366930Y1713217D01*
X1365535Y1711758D01*
X1364605Y1709675D01*
X1364295Y1707800D01*
X1370805D01*
G01X1379950Y1707383D02*
X1379640Y1707592D01*
Y1708008D01*
X1379950Y1708217D01*
X1380260Y1708008D01*
Y1707592D01*
X1379950Y1707383D01*
G01X1392350Y1720300D02*
X1391110Y1719883D01*
X1390180Y1718842D01*
X1389560Y1717592D01*
X1389095Y1715925D01*
X1388940Y1714050D01*
X1389095Y1712175D01*
X1389560Y1710508D01*
X1390180Y1709258D01*
X1391110Y1708217D01*
X1392350Y1707800D01*
X1393590Y1708217D01*
X1394520Y1709258D01*
X1395140Y1710508D01*
X1395605Y1712175D01*
X1395760Y1714050D01*
X1395605Y1715925D01*
X1395140Y1717592D01*
X1394520Y1718842D01*
X1393590Y1719883D01*
X1392350Y1720300D01*
G01X1351895Y1739116D02*
X1353135Y1738075D01*
X1354530Y1737450D01*
X1355770D01*
X1357010Y1738075D01*
X1357940Y1739116D01*
X1358405Y1740575D01*
X1358095Y1742033D01*
X1357320Y1743283D01*
X1355925Y1744117D01*
X1354065Y1744533D01*
X1352980Y1745367D01*
X1352515Y1746825D01*
X1352825Y1748283D01*
X1353600Y1749325D01*
X1354685Y1749950D01*
X1355770D01*
X1356855Y1749533D01*
X1357785Y1748492D01*
G01X1365690Y1749950D02*
X1369410D01*
G01X1367550D02*
Y1737450D01*
G01X1365690D02*
X1369410D01*
G01X1377005Y1749950D02*
X1382895D01*
X1377005Y1737450D01*
X1382895D01*
G01X1395450D02*
X1389250D01*
Y1749950D01*
X1395450D01*
G01X1392970Y1743908D02*
X1389250D01*
G01X1468300Y1756200D02*
Y1475200D01*
G01X1472485Y1511100D02*
Y1523600D01*
X1479615Y1511100D01*
Y1523600D01*
G01X1488450Y1511100D02*
X1487210Y1511308D01*
X1486125Y1512141D01*
X1485195Y1513392D01*
X1484575Y1514850D01*
X1484265Y1516517D01*
Y1518183D01*
X1484575Y1519850D01*
X1485195Y1521308D01*
X1486125Y1522558D01*
X1487210Y1523392D01*
X1488450Y1523600D01*
X1489690Y1523392D01*
X1490775Y1522558D01*
X1491705Y1521308D01*
X1492325Y1519850D01*
X1492635Y1518183D01*
Y1516517D01*
X1492325Y1514850D01*
X1491705Y1513392D01*
X1490775Y1512141D01*
X1489690Y1511308D01*
X1488450Y1511100D01*
G01X1497285D02*
Y1523600D01*
X1504415Y1511100D01*
Y1523600D01*
G01X1511235Y1515267D02*
X1515265D01*
G01X1522550Y1511100D02*
Y1523600D01*
X1526270D01*
X1527510Y1522975D01*
X1528440Y1521517D01*
X1528750Y1519850D01*
X1528440Y1518183D01*
X1527665Y1516933D01*
X1526270Y1516308D01*
X1522550D01*
G01X1534950Y1523600D02*
Y1511100D01*
X1541150D01*
G01X1546575D02*
X1550450Y1523600D01*
X1554325Y1511100D01*
G01X1552930Y1515475D02*
X1547970D01*
G01X1562850Y1523600D02*
Y1511100D01*
G01X1559285Y1523600D02*
X1566415D01*
G01X1578350Y1511100D02*
X1572150D01*
Y1523600D01*
X1578350D01*
G01X1575870Y1517558D02*
X1572150D01*
G01X1584240Y1511100D02*
Y1523600D01*
X1587340D01*
X1588580Y1522975D01*
X1589510Y1522142D01*
X1590285Y1520892D01*
X1590905Y1519433D01*
X1591060Y1517350D01*
X1590905Y1515267D01*
X1590285Y1513808D01*
X1589510Y1512558D01*
X1588580Y1511725D01*
X1587340Y1511100D01*
X1584240D01*
G01X1472485Y1539200D02*
Y1551700D01*
X1479615Y1539200D01*
Y1551700D01*
G01X1488450Y1539200D02*
X1487210Y1539408D01*
X1486125Y1540241D01*
X1485195Y1541492D01*
X1484575Y1542950D01*
X1484265Y1544617D01*
Y1546283D01*
X1484575Y1547950D01*
X1485195Y1549408D01*
X1486125Y1550658D01*
X1487210Y1551492D01*
X1488450Y1551700D01*
X1489690Y1551492D01*
X1490775Y1550658D01*
X1491705Y1549408D01*
X1492325Y1547950D01*
X1492635Y1546283D01*
Y1544617D01*
X1492325Y1542950D01*
X1491705Y1541492D01*
X1490775Y1540241D01*
X1489690Y1539408D01*
X1488450Y1539200D01*
G01X1497285D02*
Y1551700D01*
X1504415Y1539200D01*
Y1551700D01*
G01X1511235Y1543367D02*
X1515265D01*
G01X1522550Y1539200D02*
Y1551700D01*
X1526270D01*
X1527510Y1551075D01*
X1528440Y1549617D01*
X1528750Y1547950D01*
X1528440Y1546283D01*
X1527665Y1545033D01*
X1526270Y1544408D01*
X1522550D01*
G01X1534950Y1551700D02*
Y1539200D01*
X1541150D01*
G01X1546575D02*
X1550450Y1551700D01*
X1554325Y1539200D01*
G01X1552930Y1543575D02*
X1547970D01*
G01X1562850Y1551700D02*
Y1539200D01*
G01X1559285Y1551700D02*
X1566415D01*
G01X1578350Y1539200D02*
X1572150D01*
Y1551700D01*
X1578350D01*
G01X1575870Y1545658D02*
X1572150D01*
G01X1584240Y1539200D02*
Y1551700D01*
X1587340D01*
X1588580Y1551075D01*
X1589510Y1550242D01*
X1590285Y1548992D01*
X1590905Y1547533D01*
X1591060Y1545450D01*
X1590905Y1543367D01*
X1590285Y1541908D01*
X1589510Y1540658D01*
X1588580Y1539825D01*
X1587340Y1539200D01*
X1584240D01*
G01X1472485Y1567300D02*
Y1579800D01*
X1479615Y1567300D01*
Y1579800D01*
G01X1488450Y1567300D02*
X1487210Y1567508D01*
X1486125Y1568341D01*
X1485195Y1569592D01*
X1484575Y1571050D01*
X1484265Y1572717D01*
Y1574383D01*
X1484575Y1576050D01*
X1485195Y1577508D01*
X1486125Y1578758D01*
X1487210Y1579592D01*
X1488450Y1579800D01*
X1489690Y1579592D01*
X1490775Y1578758D01*
X1491705Y1577508D01*
X1492325Y1576050D01*
X1492635Y1574383D01*
Y1572717D01*
X1492325Y1571050D01*
X1491705Y1569592D01*
X1490775Y1568341D01*
X1489690Y1567508D01*
X1488450Y1567300D01*
G01X1497285D02*
Y1579800D01*
X1504415Y1567300D01*
Y1579800D01*
G01X1511235Y1571467D02*
X1515265D01*
G01X1522550Y1567300D02*
Y1579800D01*
X1526270D01*
X1527510Y1579175D01*
X1528440Y1577717D01*
X1528750Y1576050D01*
X1528440Y1574383D01*
X1527665Y1573133D01*
X1526270Y1572508D01*
X1522550D01*
G01X1534950Y1579800D02*
Y1567300D01*
X1541150D01*
G01X1546575D02*
X1550450Y1579800D01*
X1554325Y1567300D01*
G01X1552930Y1571675D02*
X1547970D01*
G01X1562850Y1579800D02*
Y1567300D01*
G01X1559285Y1579800D02*
X1566415D01*
G01X1578350Y1567300D02*
X1572150D01*
Y1579800D01*
X1578350D01*
G01X1575870Y1573758D02*
X1572150D01*
G01X1584240Y1567300D02*
Y1579800D01*
X1587340D01*
X1588580Y1579175D01*
X1589510Y1578342D01*
X1590285Y1577092D01*
X1590905Y1575633D01*
X1591060Y1573550D01*
X1590905Y1571467D01*
X1590285Y1570008D01*
X1589510Y1568758D01*
X1588580Y1567925D01*
X1587340Y1567300D01*
X1584240D01*
G01X1472485Y1595400D02*
Y1607900D01*
X1479615Y1595400D01*
Y1607900D01*
G01X1488450Y1595400D02*
X1487210Y1595608D01*
X1486125Y1596441D01*
X1485195Y1597692D01*
X1484575Y1599150D01*
X1484265Y1600817D01*
Y1602483D01*
X1484575Y1604150D01*
X1485195Y1605608D01*
X1486125Y1606858D01*
X1487210Y1607692D01*
X1488450Y1607900D01*
X1489690Y1607692D01*
X1490775Y1606858D01*
X1491705Y1605608D01*
X1492325Y1604150D01*
X1492635Y1602483D01*
Y1600817D01*
X1492325Y1599150D01*
X1491705Y1597692D01*
X1490775Y1596441D01*
X1489690Y1595608D01*
X1488450Y1595400D01*
G01X1497285D02*
Y1607900D01*
X1504415Y1595400D01*
Y1607900D01*
G01X1511235Y1599567D02*
X1515265D01*
G01X1522550Y1595400D02*
Y1607900D01*
X1526270D01*
X1527510Y1607275D01*
X1528440Y1605817D01*
X1528750Y1604150D01*
X1528440Y1602483D01*
X1527665Y1601233D01*
X1526270Y1600608D01*
X1522550D01*
G01X1534950Y1607900D02*
Y1595400D01*
X1541150D01*
G01X1546575D02*
X1550450Y1607900D01*
X1554325Y1595400D01*
G01X1552930Y1599775D02*
X1547970D01*
G01X1562850Y1607900D02*
Y1595400D01*
G01X1559285Y1607900D02*
X1566415D01*
G01X1578350Y1595400D02*
X1572150D01*
Y1607900D01*
X1578350D01*
G01X1575870Y1601858D02*
X1572150D01*
G01X1584240Y1595400D02*
Y1607900D01*
X1587340D01*
X1588580Y1607275D01*
X1589510Y1606442D01*
X1590285Y1605192D01*
X1590905Y1603733D01*
X1591060Y1601650D01*
X1590905Y1599567D01*
X1590285Y1598108D01*
X1589510Y1596858D01*
X1588580Y1596025D01*
X1587340Y1595400D01*
X1584240D01*
G01X1497750Y1483000D02*
Y1495500D01*
X1501470D01*
X1502710Y1494875D01*
X1503640Y1493417D01*
X1503950Y1491750D01*
X1503640Y1490083D01*
X1502865Y1488833D01*
X1501470Y1488208D01*
X1497750D01*
G01X1510150Y1495500D02*
Y1483000D01*
X1516350D01*
G01X1521775D02*
X1525650Y1495500D01*
X1529525Y1483000D01*
G01X1528130Y1487375D02*
X1523170D01*
G01X1538050Y1495500D02*
Y1483000D01*
G01X1534485Y1495500D02*
X1541615D01*
G01X1553550Y1483000D02*
X1547350D01*
Y1495500D01*
X1553550D01*
G01X1551070Y1489458D02*
X1547350D01*
G01X1559440Y1483000D02*
Y1495500D01*
X1562540D01*
X1563780Y1494875D01*
X1564710Y1494042D01*
X1565485Y1492792D01*
X1566105Y1491333D01*
X1566260Y1489250D01*
X1566105Y1487167D01*
X1565485Y1485708D01*
X1564710Y1484458D01*
X1563780Y1483625D01*
X1562540Y1483000D01*
X1559440D01*
G01X1497750Y1623500D02*
Y1636000D01*
X1501470D01*
X1502710Y1635375D01*
X1503640Y1633917D01*
X1503950Y1632250D01*
X1503640Y1630583D01*
X1502865Y1629333D01*
X1501470Y1628708D01*
X1497750D01*
G01X1510150Y1636000D02*
Y1623500D01*
X1516350D01*
G01X1521775D02*
X1525650Y1636000D01*
X1529525Y1623500D01*
G01X1528130Y1627875D02*
X1523170D01*
G01X1538050Y1636000D02*
Y1623500D01*
G01X1534485Y1636000D02*
X1541615D01*
G01X1553550Y1623500D02*
X1547350D01*
Y1636000D01*
X1553550D01*
G01X1551070Y1629958D02*
X1547350D01*
G01X1559440Y1623500D02*
Y1636000D01*
X1562540D01*
X1563780Y1635375D01*
X1564710Y1634542D01*
X1565485Y1633292D01*
X1566105Y1631833D01*
X1566260Y1629750D01*
X1566105Y1627667D01*
X1565485Y1626208D01*
X1564710Y1624958D01*
X1563780Y1624125D01*
X1562540Y1623500D01*
X1559440D01*
G01X1497750Y1651600D02*
Y1664100D01*
X1501470D01*
X1502710Y1663475D01*
X1503640Y1662017D01*
X1503950Y1660350D01*
X1503640Y1658683D01*
X1502865Y1657433D01*
X1501470Y1656808D01*
X1497750D01*
G01X1510150Y1664100D02*
Y1651600D01*
X1516350D01*
G01X1521775D02*
X1525650Y1664100D01*
X1529525Y1651600D01*
G01X1528130Y1655975D02*
X1523170D01*
G01X1538050Y1664100D02*
Y1651600D01*
G01X1534485Y1664100D02*
X1541615D01*
G01X1553550Y1651600D02*
X1547350D01*
Y1664100D01*
X1553550D01*
G01X1551070Y1658058D02*
X1547350D01*
G01X1559440Y1651600D02*
Y1664100D01*
X1562540D01*
X1563780Y1663475D01*
X1564710Y1662642D01*
X1565485Y1661392D01*
X1566105Y1659933D01*
X1566260Y1657850D01*
X1566105Y1655767D01*
X1565485Y1654308D01*
X1564710Y1653058D01*
X1563780Y1652225D01*
X1562540Y1651600D01*
X1559440D01*
G01X1497750Y1679700D02*
Y1692200D01*
X1501470D01*
X1502710Y1691575D01*
X1503640Y1690117D01*
X1503950Y1688450D01*
X1503640Y1686783D01*
X1502865Y1685533D01*
X1501470Y1684908D01*
X1497750D01*
G01X1510150Y1692200D02*
Y1679700D01*
X1516350D01*
G01X1521775D02*
X1525650Y1692200D01*
X1529525Y1679700D01*
G01X1528130Y1684075D02*
X1523170D01*
G01X1538050Y1692200D02*
Y1679700D01*
G01X1534485Y1692200D02*
X1541615D01*
G01X1553550Y1679700D02*
X1547350D01*
Y1692200D01*
X1553550D01*
G01X1551070Y1686158D02*
X1547350D01*
G01X1559440Y1679700D02*
Y1692200D01*
X1562540D01*
X1563780Y1691575D01*
X1564710Y1690742D01*
X1565485Y1689492D01*
X1566105Y1688033D01*
X1566260Y1685950D01*
X1566105Y1683867D01*
X1565485Y1682408D01*
X1564710Y1681158D01*
X1563780Y1680325D01*
X1562540Y1679700D01*
X1559440D01*
G01X1497750Y1707800D02*
Y1720300D01*
X1501470D01*
X1502710Y1719675D01*
X1503640Y1718217D01*
X1503950Y1716550D01*
X1503640Y1714883D01*
X1502865Y1713633D01*
X1501470Y1713008D01*
X1497750D01*
G01X1510150Y1720300D02*
Y1707800D01*
X1516350D01*
G01X1521775D02*
X1525650Y1720300D01*
X1529525Y1707800D01*
G01X1528130Y1712175D02*
X1523170D01*
G01X1538050Y1720300D02*
Y1707800D01*
G01X1534485Y1720300D02*
X1541615D01*
G01X1553550Y1707800D02*
X1547350D01*
Y1720300D01*
X1553550D01*
G01X1551070Y1714258D02*
X1547350D01*
G01X1559440Y1707800D02*
Y1720300D01*
X1562540D01*
X1563780Y1719675D01*
X1564710Y1718842D01*
X1565485Y1717592D01*
X1566105Y1716133D01*
X1566260Y1714050D01*
X1566105Y1711967D01*
X1565485Y1710508D01*
X1564710Y1709258D01*
X1563780Y1708425D01*
X1562540Y1707800D01*
X1559440D01*
G01X1497750Y1737450D02*
Y1749950D01*
X1501470D01*
X1502710Y1749325D01*
X1503640Y1747867D01*
X1503950Y1746200D01*
X1503640Y1744533D01*
X1502865Y1743283D01*
X1501470Y1742658D01*
X1497750D01*
G01X1510150Y1749950D02*
Y1737450D01*
X1516350D01*
G01X1521775D02*
X1525650Y1749950D01*
X1529525Y1737450D01*
G01X1528130Y1741825D02*
X1523170D01*
G01X1538050Y1749950D02*
Y1737450D01*
G01X1534485Y1749950D02*
X1541615D01*
G01X1553550Y1737450D02*
X1547350D01*
Y1749950D01*
X1553550D01*
G01X1551070Y1743908D02*
X1547350D01*
G01X1559440Y1737450D02*
Y1749950D01*
X1562540D01*
X1563780Y1749325D01*
X1564710Y1748492D01*
X1565485Y1747242D01*
X1566105Y1745783D01*
X1566260Y1743700D01*
X1566105Y1741617D01*
X1565485Y1740158D01*
X1564710Y1738908D01*
X1563780Y1738075D01*
X1562540Y1737450D01*
X1559440D01*
G01X1595400Y1756200D02*
Y1475200D01*
G01X1624540Y1485500D02*
X1625470Y1484041D01*
X1626710Y1483208D01*
X1628105Y1483000D01*
X1629345Y1483208D01*
X1630585Y1484250D01*
X1631360Y1485500D01*
X1631515Y1486750D01*
X1631205Y1488208D01*
X1630120Y1489250D01*
X1629035Y1489667D01*
X1627640D01*
G01X1629035D02*
X1629965Y1490292D01*
X1630740Y1491333D01*
X1631050Y1492583D01*
X1630740Y1493833D01*
X1629965Y1494875D01*
X1628570Y1495500D01*
X1627175Y1495292D01*
X1625780Y1494458D01*
G01X1640350Y1495500D02*
X1639110Y1495083D01*
X1638180Y1494042D01*
X1637560Y1492792D01*
X1637095Y1491125D01*
X1636940Y1489250D01*
X1637095Y1487375D01*
X1637560Y1485708D01*
X1638180Y1484458D01*
X1639110Y1483417D01*
X1640350Y1483000D01*
X1641590Y1483417D01*
X1642520Y1484458D01*
X1643140Y1485708D01*
X1643605Y1487375D01*
X1643760Y1489250D01*
X1643605Y1491125D01*
X1643140Y1492792D01*
X1642520Y1494042D01*
X1641590Y1495083D01*
X1640350Y1495500D01*
G01X1624540Y1597900D02*
X1625470Y1596441D01*
X1626710Y1595608D01*
X1628105Y1595400D01*
X1629345Y1595608D01*
X1630585Y1596650D01*
X1631360Y1597900D01*
X1631515Y1599150D01*
X1631205Y1600608D01*
X1630120Y1601650D01*
X1629035Y1602067D01*
X1627640D01*
G01X1629035D02*
X1629965Y1602692D01*
X1630740Y1603733D01*
X1631050Y1604983D01*
X1630740Y1606233D01*
X1629965Y1607275D01*
X1628570Y1607900D01*
X1627175Y1607692D01*
X1625780Y1606858D01*
G01X1640350Y1607900D02*
X1639110Y1607483D01*
X1638180Y1606442D01*
X1637560Y1605192D01*
X1637095Y1603525D01*
X1636940Y1601650D01*
X1637095Y1599775D01*
X1637560Y1598108D01*
X1638180Y1596858D01*
X1639110Y1595817D01*
X1640350Y1595400D01*
X1641590Y1595817D01*
X1642520Y1596858D01*
X1643140Y1598108D01*
X1643605Y1599775D01*
X1643760Y1601650D01*
X1643605Y1603525D01*
X1643140Y1605192D01*
X1642520Y1606442D01*
X1641590Y1607483D01*
X1640350Y1607900D01*
G01X1627950Y1651600D02*
Y1664100D01*
X1626090Y1661600D01*
G01Y1651600D02*
X1629810D01*
G01X1640350D02*
Y1664100D01*
X1638490Y1661600D01*
G01Y1651600D02*
X1642210D01*
G01X1617410Y1679700D02*
Y1692200D01*
X1611675Y1683242D01*
X1619425D01*
G01X1627950Y1679700D02*
Y1692200D01*
X1626090Y1689700D01*
G01Y1679700D02*
X1629810D01*
G01X1637715Y1681158D02*
X1638800Y1680117D01*
X1640040Y1679700D01*
X1641280Y1680117D01*
X1642365Y1681366D01*
X1643140Y1683242D01*
X1643450Y1685117D01*
Y1687408D01*
X1643140Y1689283D01*
X1642365Y1690950D01*
X1641435Y1691783D01*
X1640350Y1692200D01*
X1639110Y1691783D01*
X1638180Y1690950D01*
X1637560Y1689700D01*
X1637250Y1688033D01*
X1637560Y1686575D01*
X1638335Y1685117D01*
X1639265Y1684283D01*
X1640350Y1684075D01*
X1641590Y1684491D01*
X1642520Y1685533D01*
X1643450Y1687408D01*
G01X1649340Y1682200D02*
X1650270Y1680741D01*
X1651510Y1679908D01*
X1652905Y1679700D01*
X1654145Y1679908D01*
X1655385Y1680950D01*
X1656160Y1682200D01*
X1656315Y1683450D01*
X1656005Y1684908D01*
X1654920Y1685950D01*
X1653835Y1686367D01*
X1652440D01*
G01X1653835D02*
X1654765Y1686992D01*
X1655540Y1688033D01*
X1655850Y1689283D01*
X1655540Y1690533D01*
X1654765Y1691575D01*
X1653370Y1692200D01*
X1651975Y1691992D01*
X1650580Y1691158D01*
G01X1615550Y1707800D02*
Y1720300D01*
X1613690Y1717800D01*
G01Y1707800D02*
X1617410D01*
G01X1625005Y1718217D02*
X1625935Y1719466D01*
X1627020Y1720092D01*
X1628260Y1720300D01*
X1629810Y1719883D01*
X1630895Y1718842D01*
X1631205Y1717592D01*
X1631050Y1716341D01*
X1630430Y1715300D01*
X1627330Y1713217D01*
X1625935Y1711758D01*
X1625005Y1709675D01*
X1624695Y1707800D01*
X1631205D01*
G01X1640040D02*
X1640350Y1710508D01*
X1640815Y1712800D01*
X1641435Y1714883D01*
X1642210Y1717175D01*
X1643450Y1720300D01*
X1637250D01*
G01X1650115Y1709258D02*
X1651200Y1708217D01*
X1652440Y1707800D01*
X1653680Y1708217D01*
X1654765Y1709466D01*
X1655540Y1711342D01*
X1655850Y1713217D01*
Y1715508D01*
X1655540Y1717383D01*
X1654765Y1719050D01*
X1653835Y1719883D01*
X1652750Y1720300D01*
X1651510Y1719883D01*
X1650580Y1719050D01*
X1649960Y1717800D01*
X1649650Y1716133D01*
X1649960Y1714675D01*
X1650735Y1713217D01*
X1651665Y1712383D01*
X1652750Y1712175D01*
X1653990Y1712591D01*
X1654920Y1713633D01*
X1655850Y1715508D01*
G01X1621750Y1737450D02*
X1620510Y1737658D01*
X1619425Y1738491D01*
X1618495Y1739742D01*
X1617875Y1741200D01*
X1617565Y1742867D01*
Y1744533D01*
X1617875Y1746200D01*
X1618495Y1747658D01*
X1619425Y1748908D01*
X1620510Y1749742D01*
X1621750Y1749950D01*
X1622990Y1749742D01*
X1624075Y1748908D01*
X1625005Y1747658D01*
X1625625Y1746200D01*
X1625935Y1744533D01*
Y1742867D01*
X1625625Y1741200D01*
X1625005Y1739742D01*
X1624075Y1738491D01*
X1622990Y1737658D01*
X1621750Y1737450D01*
G01X1622990Y1740783D02*
X1624850Y1737450D01*
G01X1634150Y1749950D02*
Y1737450D01*
G01X1630585Y1749950D02*
X1637715D01*
G01X1646550Y1737450D02*
Y1743075D01*
X1643450Y1749950D01*
G01X1649650D02*
X1646550Y1743075D01*
G01X1631205Y1521517D02*
X1632135Y1522766D01*
X1633220Y1523392D01*
X1634460Y1523600D01*
X1636010Y1523183D01*
X1637095Y1522142D01*
X1637405Y1520892D01*
X1637250Y1519641D01*
X1636630Y1518600D01*
X1633530Y1516517D01*
X1632135Y1515058D01*
X1631205Y1512975D01*
X1630895Y1511100D01*
X1637405D01*
G01X1634150Y1539200D02*
X1635235Y1539408D01*
X1636475Y1540033D01*
X1637250Y1541075D01*
X1637560Y1542533D01*
X1637250Y1543991D01*
X1636320Y1545242D01*
X1634925Y1545867D01*
X1633375D01*
X1632445Y1546283D01*
X1631670Y1547325D01*
X1631360Y1548783D01*
X1631825Y1550242D01*
X1632910Y1551283D01*
X1634150Y1551700D01*
X1635390Y1551283D01*
X1636475Y1550242D01*
X1636940Y1548783D01*
X1636630Y1547325D01*
X1635855Y1546283D01*
X1634925Y1545867D01*
X1633375D01*
X1631980Y1545242D01*
X1631050Y1543991D01*
X1630740Y1542533D01*
X1631050Y1541075D01*
X1631825Y1540033D01*
X1633065Y1539408D01*
X1634150Y1539200D01*
G01X1630740Y1569175D02*
X1631670Y1568133D01*
X1632755Y1567508D01*
X1634150Y1567300D01*
X1635545Y1567717D01*
X1636630Y1568550D01*
X1637405Y1570008D01*
X1637560Y1571675D01*
X1637250Y1573342D01*
X1636475Y1574383D01*
X1635390Y1575217D01*
X1634305Y1575425D01*
X1633220Y1575217D01*
X1631825Y1574383D01*
X1632290Y1579800D01*
X1636475D01*
G01X1631205Y1633917D02*
X1632135Y1635166D01*
X1633220Y1635792D01*
X1634460Y1636000D01*
X1636010Y1635583D01*
X1637095Y1634542D01*
X1637405Y1633292D01*
X1637250Y1632041D01*
X1636630Y1631000D01*
X1633530Y1628917D01*
X1632135Y1627458D01*
X1631205Y1625375D01*
X1630895Y1623500D01*
X1637405D01*
G01X-11124Y516717D02*
X-11457Y516184D01*
X-11657Y515584D01*
Y515050D01*
X-11457Y514517D01*
X-11124Y514117D01*
X-10657Y513917D01*
X-10190Y514050D01*
X-9790Y514384D01*
X-9524Y514984D01*
X-9390Y515784D01*
X-9124Y516250D01*
X-8657Y516450D01*
X-8190Y516317D01*
X-7857Y515984D01*
X-7657Y515517D01*
Y515050D01*
X-7790Y514584D01*
X-8124Y514184D01*
G01X-11657Y510717D02*
X-7657D01*
G01X-8990Y506117D02*
X-11657D01*
G01X-7924D02*
X-7857Y506250D01*
X-7724D01*
X-7657Y506117D01*
X-7724Y505984D01*
X-7857D01*
X-7924Y506117D01*
G01X-7657Y501517D02*
X-11657D01*
G01X-8990Y502450D02*
Y500584D01*
G01X-157Y508317D02*
X-3157Y511317D01*
Y505317D01*
X-157Y508317D01*
X-8657D01*
G01X-11724Y818890D02*
X-12057Y818357D01*
X-12257Y817757D01*
Y817223D01*
X-12057Y816690D01*
X-11724Y816290D01*
X-11257Y816090D01*
X-10790Y816223D01*
X-10390Y816557D01*
X-10124Y817157D01*
X-9990Y817957D01*
X-9724Y818423D01*
X-9257Y818623D01*
X-8790Y818490D01*
X-8457Y818157D01*
X-8257Y817690D01*
Y817223D01*
X-8390Y816757D01*
X-8724Y816357D01*
G01X-12257Y812890D02*
X-8257D01*
G01X-9590Y808290D02*
X-12257D01*
G01X-8524D02*
X-8457Y808423D01*
X-8324D01*
X-8257Y808290D01*
X-8324Y808157D01*
X-8457D01*
X-8524Y808290D01*
G01X-8257Y803690D02*
X-12257D01*
G01X-9590Y804623D02*
Y802757D01*
G01X-257Y810290D02*
X-9757D01*
G01X-5257Y808795D02*
X-257Y810290D01*
X-5257Y811785D01*
Y808795D01*
G01X-11124Y1500969D02*
X-11457Y1500436D01*
X-11657Y1499836D01*
Y1499302D01*
X-11457Y1498769D01*
X-11124Y1498369D01*
X-10657Y1498169D01*
X-10190Y1498302D01*
X-9790Y1498636D01*
X-9524Y1499236D01*
X-9390Y1500036D01*
X-9124Y1500502D01*
X-8657Y1500702D01*
X-8190Y1500569D01*
X-7857Y1500236D01*
X-7657Y1499769D01*
Y1499302D01*
X-7790Y1498836D01*
X-8124Y1498436D01*
G01X-11657Y1494969D02*
X-7657D01*
G01X-8990Y1490369D02*
X-11657D01*
G01X-7924D02*
X-7857Y1490502D01*
X-7724D01*
X-7657Y1490369D01*
X-7724Y1490236D01*
X-7857D01*
X-7924Y1490369D01*
G01X-7657Y1485769D02*
X-11657D01*
G01X-8990Y1486702D02*
Y1484836D01*
G01X-157Y1492569D02*
X-3157Y1495569D01*
Y1489569D01*
X-157Y1492569D01*
X-8657D01*
G01X-11724Y1803142D02*
X-12057Y1802609D01*
X-12257Y1802009D01*
Y1801475D01*
X-12057Y1800942D01*
X-11724Y1800542D01*
X-11257Y1800342D01*
X-10790Y1800475D01*
X-10390Y1800809D01*
X-10124Y1801409D01*
X-9990Y1802209D01*
X-9724Y1802675D01*
X-9257Y1802875D01*
X-8790Y1802742D01*
X-8457Y1802409D01*
X-8257Y1801942D01*
Y1801475D01*
X-8390Y1801009D01*
X-8724Y1800609D01*
G01X-12257Y1797142D02*
X-8257D01*
G01X-9590Y1792542D02*
X-12257D01*
G01X-8524D02*
X-8457Y1792675D01*
X-8324D01*
X-8257Y1792542D01*
X-8324Y1792409D01*
X-8457D01*
X-8524Y1792542D01*
G01X-8257Y1787942D02*
X-12257D01*
G01X-9590Y1788875D02*
Y1787009D01*
G01X-257Y1794542D02*
X-9757D01*
G01X-5257Y1793047D02*
X-257Y1794542D01*
X-5257Y1796037D01*
Y1793047D01*
G01X0Y727946D02*
Y423026D01*
X1969Y421057D01*
X19883D01*
G02Y413577I0J-3740D01*
G01X1969D01*
X0Y411608D01*
Y342908D01*
G01Y727946D02*
Y423026D01*
X1969Y421057D01*
X19883D01*
G02Y413577I0J-3740D01*
G01X1969D01*
X0Y411608D01*
Y342908D01*
G01X19842Y823050D02*
X1970D01*
X1Y821081D01*
Y752381D01*
G01Y885451D02*
Y832499D01*
X1970Y830530D01*
X19883D01*
G02Y823050I0J-3740D01*
G01X19842D01*
G01X0Y1712198D02*
Y1407278D01*
X1969Y1405309D01*
X19883D01*
G02Y1397829I0J-3740D01*
G01X1969D01*
X0Y1395860D01*
Y1327160D01*
G01Y1712198D02*
Y1407278D01*
X1969Y1405309D01*
X19883D01*
G02Y1397829I0J-3740D01*
G01X1969D01*
X0Y1395860D01*
Y1327160D01*
G01X19842Y1807302D02*
X1970D01*
X1Y1805333D01*
Y1736633D01*
G01Y1869703D02*
Y1816751D01*
X1970Y1814782D01*
X19883D01*
G02Y1807302I0J-3740D01*
G01X19842D01*
G01X69598Y28794D02*
X70065Y29194D01*
X70331Y29728D01*
X70398Y30328D01*
X70331Y30861D01*
X69998Y31394D01*
X69598Y31728D01*
X69198Y31794D01*
X68731Y31661D01*
X68398Y31194D01*
X68265Y30728D01*
Y30128D01*
G01Y30728D02*
X68065Y31128D01*
X67731Y31461D01*
X67331Y31594D01*
X66931Y31461D01*
X66598Y31128D01*
X66398Y30528D01*
X66465Y29928D01*
X66731Y29328D01*
G01X67065Y33594D02*
X66665Y33994D01*
X66465Y34461D01*
X66398Y34994D01*
X66531Y35661D01*
X66865Y36128D01*
X67265Y36261D01*
X67665Y36194D01*
X67998Y35928D01*
X68665Y34594D01*
X69131Y33994D01*
X69798Y33594D01*
X70398Y33461D01*
Y36261D01*
G01Y38061D02*
X66398Y40861D01*
G01Y38061D02*
X70398Y40861D01*
G01Y43928D02*
X69531Y44061D01*
X68798Y44261D01*
X68131Y44528D01*
X67398Y44861D01*
X66398Y45394D01*
Y42728D01*
G01X69798Y47194D02*
X70131Y47594D01*
X70331Y48061D01*
X70398Y48661D01*
X70265Y49261D01*
X69998Y49728D01*
X69531Y50061D01*
X68998Y50128D01*
X68465Y49994D01*
X68131Y49661D01*
X67865Y49194D01*
X67798Y48728D01*
X67865Y48261D01*
X68131Y47661D01*
X66398Y47861D01*
Y49661D01*
G01X69598Y157794D02*
X70065Y158194D01*
X70331Y158728D01*
X70398Y159328D01*
X70331Y159861D01*
X69998Y160394D01*
X69598Y160728D01*
X69198Y160794D01*
X68731Y160661D01*
X68398Y160194D01*
X68265Y159728D01*
Y159128D01*
G01Y159728D02*
X68065Y160128D01*
X67731Y160461D01*
X67331Y160594D01*
X66931Y160461D01*
X66598Y160128D01*
X66398Y159528D01*
X66465Y158928D01*
X66731Y158328D01*
G01X67065Y162594D02*
X66665Y162994D01*
X66465Y163461D01*
X66398Y163994D01*
X66531Y164661D01*
X66865Y165128D01*
X67265Y165261D01*
X67665Y165194D01*
X67998Y164928D01*
X68665Y163594D01*
X69131Y162994D01*
X69798Y162594D01*
X70398Y162461D01*
Y165261D01*
G01Y167061D02*
X66398Y169861D01*
G01Y167061D02*
X70398Y169861D01*
G01Y172928D02*
X69531Y173061D01*
X68798Y173261D01*
X68131Y173528D01*
X67398Y173861D01*
X66398Y174394D01*
Y171728D01*
G01X69798Y176194D02*
X70131Y176594D01*
X70331Y177061D01*
X70398Y177661D01*
X70265Y178261D01*
X69998Y178728D01*
X69531Y179061D01*
X68998Y179128D01*
X68465Y178994D01*
X68131Y178661D01*
X67865Y178194D01*
X67798Y177728D01*
X67865Y177261D01*
X68131Y176661D01*
X66398Y176861D01*
Y178661D01*
G01X69598Y434306D02*
X70065Y434706D01*
X70331Y435240D01*
X70398Y435840D01*
X70331Y436373D01*
X69998Y436906D01*
X69598Y437240D01*
X69198Y437306D01*
X68731Y437173D01*
X68398Y436706D01*
X68265Y436240D01*
Y435640D01*
G01Y436240D02*
X68065Y436640D01*
X67731Y436973D01*
X67331Y437106D01*
X66931Y436973D01*
X66598Y436640D01*
X66398Y436040D01*
X66465Y435440D01*
X66731Y434840D01*
G01X67065Y439106D02*
X66665Y439506D01*
X66465Y439973D01*
X66398Y440506D01*
X66531Y441173D01*
X66865Y441640D01*
X67265Y441773D01*
X67665Y441706D01*
X67998Y441440D01*
X68665Y440106D01*
X69131Y439506D01*
X69798Y439106D01*
X70398Y438973D01*
Y441773D01*
G01Y443573D02*
X66398Y446373D01*
G01Y443573D02*
X70398Y446373D01*
G01Y449440D02*
X69531Y449573D01*
X68798Y449773D01*
X68131Y450040D01*
X67398Y450373D01*
X66398Y450906D01*
Y448240D01*
G01X69798Y452706D02*
X70131Y453106D01*
X70331Y453573D01*
X70398Y454173D01*
X70265Y454773D01*
X69998Y455240D01*
X69531Y455573D01*
X68998Y455640D01*
X68465Y455506D01*
X68131Y455173D01*
X67865Y454706D01*
X67798Y454240D01*
X67865Y453773D01*
X68131Y453173D01*
X66398Y453373D01*
Y455173D01*
G01X69598Y563306D02*
X70065Y563706D01*
X70331Y564240D01*
X70398Y564840D01*
X70331Y565373D01*
X69998Y565906D01*
X69598Y566240D01*
X69198Y566306D01*
X68731Y566173D01*
X68398Y565706D01*
X68265Y565240D01*
Y564640D01*
G01Y565240D02*
X68065Y565640D01*
X67731Y565973D01*
X67331Y566106D01*
X66931Y565973D01*
X66598Y565640D01*
X66398Y565040D01*
X66465Y564440D01*
X66731Y563840D01*
G01X67065Y568106D02*
X66665Y568506D01*
X66465Y568973D01*
X66398Y569506D01*
X66531Y570173D01*
X66865Y570640D01*
X67265Y570773D01*
X67665Y570706D01*
X67998Y570440D01*
X68665Y569106D01*
X69131Y568506D01*
X69798Y568106D01*
X70398Y567973D01*
Y570773D01*
G01Y572573D02*
X66398Y575373D01*
G01Y572573D02*
X70398Y575373D01*
G01Y578440D02*
X69531Y578573D01*
X68798Y578773D01*
X68131Y579040D01*
X67398Y579373D01*
X66398Y579906D01*
Y577240D01*
G01X69798Y581706D02*
X70131Y582106D01*
X70331Y582573D01*
X70398Y583173D01*
X70265Y583773D01*
X69998Y584240D01*
X69531Y584573D01*
X68998Y584640D01*
X68465Y584506D01*
X68131Y584173D01*
X67865Y583706D01*
X67798Y583240D01*
X67865Y582773D01*
X68131Y582173D01*
X66398Y582373D01*
Y584173D01*
G01X69598Y839818D02*
X70065Y840218D01*
X70331Y840752D01*
X70398Y841352D01*
X70331Y841885D01*
X69998Y842418D01*
X69598Y842752D01*
X69198Y842818D01*
X68731Y842685D01*
X68398Y842218D01*
X68265Y841752D01*
Y841152D01*
G01Y841752D02*
X68065Y842152D01*
X67731Y842485D01*
X67331Y842618D01*
X66931Y842485D01*
X66598Y842152D01*
X66398Y841552D01*
X66465Y840952D01*
X66731Y840352D01*
G01X67065Y844618D02*
X66665Y845018D01*
X66465Y845485D01*
X66398Y846018D01*
X66531Y846685D01*
X66865Y847152D01*
X67265Y847285D01*
X67665Y847218D01*
X67998Y846952D01*
X68665Y845618D01*
X69131Y845018D01*
X69798Y844618D01*
X70398Y844485D01*
Y847285D01*
G01Y849085D02*
X66398Y851885D01*
G01Y849085D02*
X70398Y851885D01*
G01Y854952D02*
X69531Y855085D01*
X68798Y855285D01*
X68131Y855552D01*
X67398Y855885D01*
X66398Y856418D01*
Y853752D01*
G01X69798Y858218D02*
X70131Y858618D01*
X70331Y859085D01*
X70398Y859685D01*
X70265Y860285D01*
X69998Y860752D01*
X69531Y861085D01*
X68998Y861152D01*
X68465Y861018D01*
X68131Y860685D01*
X67865Y860218D01*
X67798Y859752D01*
X67865Y859285D01*
X68131Y858685D01*
X66398Y858885D01*
Y860685D01*
G01X69598Y968818D02*
X70065Y969218D01*
X70331Y969752D01*
X70398Y970352D01*
X70331Y970885D01*
X69998Y971418D01*
X69598Y971752D01*
X69198Y971818D01*
X68731Y971685D01*
X68398Y971218D01*
X68265Y970752D01*
Y970152D01*
G01Y970752D02*
X68065Y971152D01*
X67731Y971485D01*
X67331Y971618D01*
X66931Y971485D01*
X66598Y971152D01*
X66398Y970552D01*
X66465Y969952D01*
X66731Y969352D01*
G01X67065Y973618D02*
X66665Y974018D01*
X66465Y974485D01*
X66398Y975018D01*
X66531Y975685D01*
X66865Y976152D01*
X67265Y976285D01*
X67665Y976218D01*
X67998Y975952D01*
X68665Y974618D01*
X69131Y974018D01*
X69798Y973618D01*
X70398Y973485D01*
Y976285D01*
G01Y978085D02*
X66398Y980885D01*
G01Y978085D02*
X70398Y980885D01*
G01Y983952D02*
X69531Y984085D01*
X68798Y984285D01*
X68131Y984552D01*
X67398Y984885D01*
X66398Y985418D01*
Y982752D01*
G01X69798Y987218D02*
X70131Y987618D01*
X70331Y988085D01*
X70398Y988685D01*
X70265Y989285D01*
X69998Y989752D01*
X69531Y990085D01*
X68998Y990152D01*
X68465Y990018D01*
X68131Y989685D01*
X67865Y989218D01*
X67798Y988752D01*
X67865Y988285D01*
X68131Y987685D01*
X66398Y987885D01*
Y989685D01*
G01X69598Y1245330D02*
X70065Y1245730D01*
X70331Y1246264D01*
X70398Y1246864D01*
X70331Y1247397D01*
X69998Y1247930D01*
X69598Y1248264D01*
X69198Y1248330D01*
X68731Y1248197D01*
X68398Y1247730D01*
X68265Y1247264D01*
Y1246664D01*
G01Y1247264D02*
X68065Y1247664D01*
X67731Y1247997D01*
X67331Y1248130D01*
X66931Y1247997D01*
X66598Y1247664D01*
X66398Y1247064D01*
X66465Y1246464D01*
X66731Y1245864D01*
G01X67065Y1250130D02*
X66665Y1250530D01*
X66465Y1250997D01*
X66398Y1251530D01*
X66531Y1252197D01*
X66865Y1252664D01*
X67265Y1252797D01*
X67665Y1252730D01*
X67998Y1252464D01*
X68665Y1251130D01*
X69131Y1250530D01*
X69798Y1250130D01*
X70398Y1249997D01*
Y1252797D01*
G01Y1254597D02*
X66398Y1257397D01*
G01Y1254597D02*
X70398Y1257397D01*
G01Y1260464D02*
X69531Y1260597D01*
X68798Y1260797D01*
X68131Y1261064D01*
X67398Y1261397D01*
X66398Y1261930D01*
Y1259264D01*
G01X69798Y1263730D02*
X70131Y1264130D01*
X70331Y1264597D01*
X70398Y1265197D01*
X70265Y1265797D01*
X69998Y1266264D01*
X69531Y1266597D01*
X68998Y1266664D01*
X68465Y1266530D01*
X68131Y1266197D01*
X67865Y1265730D01*
X67798Y1265264D01*
X67865Y1264797D01*
X68131Y1264197D01*
X66398Y1264397D01*
Y1266197D01*
G01X69598Y1374330D02*
X70065Y1374730D01*
X70331Y1375264D01*
X70398Y1375864D01*
X70331Y1376397D01*
X69998Y1376930D01*
X69598Y1377264D01*
X69198Y1377330D01*
X68731Y1377197D01*
X68398Y1376730D01*
X68265Y1376264D01*
Y1375664D01*
G01Y1376264D02*
X68065Y1376664D01*
X67731Y1376997D01*
X67331Y1377130D01*
X66931Y1376997D01*
X66598Y1376664D01*
X66398Y1376064D01*
X66465Y1375464D01*
X66731Y1374864D01*
G01X67065Y1379130D02*
X66665Y1379530D01*
X66465Y1379997D01*
X66398Y1380530D01*
X66531Y1381197D01*
X66865Y1381664D01*
X67265Y1381797D01*
X67665Y1381730D01*
X67998Y1381464D01*
X68665Y1380130D01*
X69131Y1379530D01*
X69798Y1379130D01*
X70398Y1378997D01*
Y1381797D01*
G01Y1383597D02*
X66398Y1386397D01*
G01Y1383597D02*
X70398Y1386397D01*
G01Y1389464D02*
X69531Y1389597D01*
X68798Y1389797D01*
X68131Y1390064D01*
X67398Y1390397D01*
X66398Y1390930D01*
Y1388264D01*
G01X69798Y1392730D02*
X70131Y1393130D01*
X70331Y1393597D01*
X70398Y1394197D01*
X70265Y1394797D01*
X69998Y1395264D01*
X69531Y1395597D01*
X68998Y1395664D01*
X68465Y1395530D01*
X68131Y1395197D01*
X67865Y1394730D01*
X67798Y1394264D01*
X67865Y1393797D01*
X68131Y1393197D01*
X66398Y1393397D01*
Y1395197D01*
G01X69598Y1650842D02*
X70065Y1651242D01*
X70331Y1651776D01*
X70398Y1652376D01*
X70331Y1652909D01*
X69998Y1653442D01*
X69598Y1653776D01*
X69198Y1653842D01*
X68731Y1653709D01*
X68398Y1653242D01*
X68265Y1652776D01*
Y1652176D01*
G01Y1652776D02*
X68065Y1653176D01*
X67731Y1653509D01*
X67331Y1653642D01*
X66931Y1653509D01*
X66598Y1653176D01*
X66398Y1652576D01*
X66465Y1651976D01*
X66731Y1651376D01*
G01X67065Y1655642D02*
X66665Y1656042D01*
X66465Y1656509D01*
X66398Y1657042D01*
X66531Y1657709D01*
X66865Y1658176D01*
X67265Y1658309D01*
X67665Y1658242D01*
X67998Y1657976D01*
X68665Y1656642D01*
X69131Y1656042D01*
X69798Y1655642D01*
X70398Y1655509D01*
Y1658309D01*
G01Y1660109D02*
X66398Y1662909D01*
G01Y1660109D02*
X70398Y1662909D01*
G01Y1665976D02*
X69531Y1666109D01*
X68798Y1666309D01*
X68131Y1666576D01*
X67398Y1666909D01*
X66398Y1667442D01*
Y1664776D01*
G01X69798Y1669242D02*
X70131Y1669642D01*
X70331Y1670109D01*
X70398Y1670709D01*
X70265Y1671309D01*
X69998Y1671776D01*
X69531Y1672109D01*
X68998Y1672176D01*
X68465Y1672042D01*
X68131Y1671709D01*
X67865Y1671242D01*
X67798Y1670776D01*
X67865Y1670309D01*
X68131Y1669709D01*
X66398Y1669909D01*
Y1671709D01*
G01X69598Y1779842D02*
X70065Y1780242D01*
X70331Y1780776D01*
X70398Y1781376D01*
X70331Y1781909D01*
X69998Y1782442D01*
X69598Y1782776D01*
X69198Y1782842D01*
X68731Y1782709D01*
X68398Y1782242D01*
X68265Y1781776D01*
Y1781176D01*
G01Y1781776D02*
X68065Y1782176D01*
X67731Y1782509D01*
X67331Y1782642D01*
X66931Y1782509D01*
X66598Y1782176D01*
X66398Y1781576D01*
X66465Y1780976D01*
X66731Y1780376D01*
G01X67065Y1784642D02*
X66665Y1785042D01*
X66465Y1785509D01*
X66398Y1786042D01*
X66531Y1786709D01*
X66865Y1787176D01*
X67265Y1787309D01*
X67665Y1787242D01*
X67998Y1786976D01*
X68665Y1785642D01*
X69131Y1785042D01*
X69798Y1784642D01*
X70398Y1784509D01*
Y1787309D01*
G01Y1789109D02*
X66398Y1791909D01*
G01Y1789109D02*
X70398Y1791909D01*
G01Y1794976D02*
X69531Y1795109D01*
X68798Y1795309D01*
X68131Y1795576D01*
X67398Y1795909D01*
X66398Y1796442D01*
Y1793776D01*
G01X69798Y1798242D02*
X70131Y1798642D01*
X70331Y1799109D01*
X70398Y1799709D01*
X70265Y1800309D01*
X69998Y1800776D01*
X69531Y1801109D01*
X68998Y1801176D01*
X68465Y1801042D01*
X68131Y1800709D01*
X67865Y1800242D01*
X67798Y1799776D01*
X67865Y1799309D01*
X68131Y1798709D01*
X66398Y1798909D01*
Y1800709D01*
G01X169023Y190950D02*
X169490Y191350D01*
X169756Y191884D01*
X169823Y192484D01*
X169756Y193017D01*
X169423Y193550D01*
X169023Y193884D01*
X168623Y193950D01*
X168156Y193817D01*
X167823Y193350D01*
X167690Y192884D01*
Y192284D01*
G01Y192884D02*
X167490Y193284D01*
X167156Y193617D01*
X166756Y193750D01*
X166356Y193617D01*
X166023Y193284D01*
X165823Y192684D01*
X165890Y192084D01*
X166156Y191484D01*
G01X166490Y195750D02*
X166090Y196150D01*
X165890Y196617D01*
X165823Y197150D01*
X165956Y197817D01*
X166290Y198284D01*
X166690Y198417D01*
X167090Y198350D01*
X167423Y198084D01*
X168090Y196750D01*
X168556Y196150D01*
X169223Y195750D01*
X169823Y195617D01*
Y198417D01*
G01Y200217D02*
X165823Y203017D01*
G01Y200217D02*
X169823Y203017D01*
G01Y206084D02*
X168956Y206217D01*
X168223Y206417D01*
X167556Y206684D01*
X166823Y207017D01*
X165823Y207550D01*
Y204884D01*
G01X169223Y209350D02*
X169556Y209750D01*
X169756Y210217D01*
X169823Y210817D01*
X169690Y211417D01*
X169423Y211884D01*
X168956Y212217D01*
X168423Y212284D01*
X167890Y212150D01*
X167556Y211817D01*
X167290Y211350D01*
X167223Y210884D01*
X167290Y210417D01*
X167556Y209817D01*
X165823Y210017D01*
Y211817D01*
G01X169023Y319950D02*
X169490Y320350D01*
X169756Y320884D01*
X169823Y321484D01*
X169756Y322017D01*
X169423Y322550D01*
X169023Y322884D01*
X168623Y322950D01*
X168156Y322817D01*
X167823Y322350D01*
X167690Y321884D01*
Y321284D01*
G01Y321884D02*
X167490Y322284D01*
X167156Y322617D01*
X166756Y322750D01*
X166356Y322617D01*
X166023Y322284D01*
X165823Y321684D01*
X165890Y321084D01*
X166156Y320484D01*
G01X166490Y324750D02*
X166090Y325150D01*
X165890Y325617D01*
X165823Y326150D01*
X165956Y326817D01*
X166290Y327284D01*
X166690Y327417D01*
X167090Y327350D01*
X167423Y327084D01*
X168090Y325750D01*
X168556Y325150D01*
X169223Y324750D01*
X169823Y324617D01*
Y327417D01*
G01Y329217D02*
X165823Y332017D01*
G01Y329217D02*
X169823Y332017D01*
G01Y335084D02*
X168956Y335217D01*
X168223Y335417D01*
X167556Y335684D01*
X166823Y336017D01*
X165823Y336550D01*
Y333884D01*
G01X169223Y338350D02*
X169556Y338750D01*
X169756Y339217D01*
X169823Y339817D01*
X169690Y340417D01*
X169423Y340884D01*
X168956Y341217D01*
X168423Y341284D01*
X167890Y341150D01*
X167556Y340817D01*
X167290Y340350D01*
X167223Y339884D01*
X167290Y339417D01*
X167556Y338817D01*
X165823Y339017D01*
Y340817D01*
G01X169023Y596462D02*
X169490Y596862D01*
X169756Y597396D01*
X169823Y597996D01*
X169756Y598529D01*
X169423Y599062D01*
X169023Y599396D01*
X168623Y599462D01*
X168156Y599329D01*
X167823Y598862D01*
X167690Y598396D01*
Y597796D01*
G01Y598396D02*
X167490Y598796D01*
X167156Y599129D01*
X166756Y599262D01*
X166356Y599129D01*
X166023Y598796D01*
X165823Y598196D01*
X165890Y597596D01*
X166156Y596996D01*
G01X166490Y601262D02*
X166090Y601662D01*
X165890Y602129D01*
X165823Y602662D01*
X165956Y603329D01*
X166290Y603796D01*
X166690Y603929D01*
X167090Y603862D01*
X167423Y603596D01*
X168090Y602262D01*
X168556Y601662D01*
X169223Y601262D01*
X169823Y601129D01*
Y603929D01*
G01Y605729D02*
X165823Y608529D01*
G01Y605729D02*
X169823Y608529D01*
G01Y611596D02*
X168956Y611729D01*
X168223Y611929D01*
X167556Y612196D01*
X166823Y612529D01*
X165823Y613062D01*
Y610396D01*
G01X169223Y614862D02*
X169556Y615262D01*
X169756Y615729D01*
X169823Y616329D01*
X169690Y616929D01*
X169423Y617396D01*
X168956Y617729D01*
X168423Y617796D01*
X167890Y617662D01*
X167556Y617329D01*
X167290Y616862D01*
X167223Y616396D01*
X167290Y615929D01*
X167556Y615329D01*
X165823Y615529D01*
Y617329D01*
G01X169023Y725462D02*
X169490Y725862D01*
X169756Y726396D01*
X169823Y726996D01*
X169756Y727529D01*
X169423Y728062D01*
X169023Y728396D01*
X168623Y728462D01*
X168156Y728329D01*
X167823Y727862D01*
X167690Y727396D01*
Y726796D01*
G01Y727396D02*
X167490Y727796D01*
X167156Y728129D01*
X166756Y728262D01*
X166356Y728129D01*
X166023Y727796D01*
X165823Y727196D01*
X165890Y726596D01*
X166156Y725996D01*
G01X166490Y730262D02*
X166090Y730662D01*
X165890Y731129D01*
X165823Y731662D01*
X165956Y732329D01*
X166290Y732796D01*
X166690Y732929D01*
X167090Y732862D01*
X167423Y732596D01*
X168090Y731262D01*
X168556Y730662D01*
X169223Y730262D01*
X169823Y730129D01*
Y732929D01*
G01Y734729D02*
X165823Y737529D01*
G01Y734729D02*
X169823Y737529D01*
G01Y740596D02*
X168956Y740729D01*
X168223Y740929D01*
X167556Y741196D01*
X166823Y741529D01*
X165823Y742062D01*
Y739396D01*
G01X169223Y743862D02*
X169556Y744262D01*
X169756Y744729D01*
X169823Y745329D01*
X169690Y745929D01*
X169423Y746396D01*
X168956Y746729D01*
X168423Y746796D01*
X167890Y746662D01*
X167556Y746329D01*
X167290Y745862D01*
X167223Y745396D01*
X167290Y744929D01*
X167556Y744329D01*
X165823Y744529D01*
Y746329D01*
G01X169023Y1001974D02*
X169490Y1002374D01*
X169756Y1002908D01*
X169823Y1003508D01*
X169756Y1004041D01*
X169423Y1004574D01*
X169023Y1004908D01*
X168623Y1004974D01*
X168156Y1004841D01*
X167823Y1004374D01*
X167690Y1003908D01*
Y1003308D01*
G01Y1003908D02*
X167490Y1004308D01*
X167156Y1004641D01*
X166756Y1004774D01*
X166356Y1004641D01*
X166023Y1004308D01*
X165823Y1003708D01*
X165890Y1003108D01*
X166156Y1002508D01*
G01X166490Y1006774D02*
X166090Y1007174D01*
X165890Y1007641D01*
X165823Y1008174D01*
X165956Y1008841D01*
X166290Y1009308D01*
X166690Y1009441D01*
X167090Y1009374D01*
X167423Y1009108D01*
X168090Y1007774D01*
X168556Y1007174D01*
X169223Y1006774D01*
X169823Y1006641D01*
Y1009441D01*
G01Y1011241D02*
X165823Y1014041D01*
G01Y1011241D02*
X169823Y1014041D01*
G01Y1017108D02*
X168956Y1017241D01*
X168223Y1017441D01*
X167556Y1017708D01*
X166823Y1018041D01*
X165823Y1018574D01*
Y1015908D01*
G01X169223Y1020374D02*
X169556Y1020774D01*
X169756Y1021241D01*
X169823Y1021841D01*
X169690Y1022441D01*
X169423Y1022908D01*
X168956Y1023241D01*
X168423Y1023308D01*
X167890Y1023174D01*
X167556Y1022841D01*
X167290Y1022374D01*
X167223Y1021908D01*
X167290Y1021441D01*
X167556Y1020841D01*
X165823Y1021041D01*
Y1022841D01*
G01X169023Y1130974D02*
X169490Y1131374D01*
X169756Y1131908D01*
X169823Y1132508D01*
X169756Y1133041D01*
X169423Y1133574D01*
X169023Y1133908D01*
X168623Y1133974D01*
X168156Y1133841D01*
X167823Y1133374D01*
X167690Y1132908D01*
Y1132308D01*
G01Y1132908D02*
X167490Y1133308D01*
X167156Y1133641D01*
X166756Y1133774D01*
X166356Y1133641D01*
X166023Y1133308D01*
X165823Y1132708D01*
X165890Y1132108D01*
X166156Y1131508D01*
G01X166490Y1135774D02*
X166090Y1136174D01*
X165890Y1136641D01*
X165823Y1137174D01*
X165956Y1137841D01*
X166290Y1138308D01*
X166690Y1138441D01*
X167090Y1138374D01*
X167423Y1138108D01*
X168090Y1136774D01*
X168556Y1136174D01*
X169223Y1135774D01*
X169823Y1135641D01*
Y1138441D01*
G01Y1140241D02*
X165823Y1143041D01*
G01Y1140241D02*
X169823Y1143041D01*
G01Y1146108D02*
X168956Y1146241D01*
X168223Y1146441D01*
X167556Y1146708D01*
X166823Y1147041D01*
X165823Y1147574D01*
Y1144908D01*
G01X169223Y1149374D02*
X169556Y1149774D01*
X169756Y1150241D01*
X169823Y1150841D01*
X169690Y1151441D01*
X169423Y1151908D01*
X168956Y1152241D01*
X168423Y1152308D01*
X167890Y1152174D01*
X167556Y1151841D01*
X167290Y1151374D01*
X167223Y1150908D01*
X167290Y1150441D01*
X167556Y1149841D01*
X165823Y1150041D01*
Y1151841D01*
G01X169023Y1407486D02*
X169490Y1407886D01*
X169756Y1408420D01*
X169823Y1409020D01*
X169756Y1409553D01*
X169423Y1410086D01*
X169023Y1410420D01*
X168623Y1410486D01*
X168156Y1410353D01*
X167823Y1409886D01*
X167690Y1409420D01*
Y1408820D01*
G01Y1409420D02*
X167490Y1409820D01*
X167156Y1410153D01*
X166756Y1410286D01*
X166356Y1410153D01*
X166023Y1409820D01*
X165823Y1409220D01*
X165890Y1408620D01*
X166156Y1408020D01*
G01X166490Y1412286D02*
X166090Y1412686D01*
X165890Y1413153D01*
X165823Y1413686D01*
X165956Y1414353D01*
X166290Y1414820D01*
X166690Y1414953D01*
X167090Y1414886D01*
X167423Y1414620D01*
X168090Y1413286D01*
X168556Y1412686D01*
X169223Y1412286D01*
X169823Y1412153D01*
Y1414953D01*
G01Y1416753D02*
X165823Y1419553D01*
G01Y1416753D02*
X169823Y1419553D01*
G01Y1422620D02*
X168956Y1422753D01*
X168223Y1422953D01*
X167556Y1423220D01*
X166823Y1423553D01*
X165823Y1424086D01*
Y1421420D01*
G01X169223Y1425886D02*
X169556Y1426286D01*
X169756Y1426753D01*
X169823Y1427353D01*
X169690Y1427953D01*
X169423Y1428420D01*
X168956Y1428753D01*
X168423Y1428820D01*
X167890Y1428686D01*
X167556Y1428353D01*
X167290Y1427886D01*
X167223Y1427420D01*
X167290Y1426953D01*
X167556Y1426353D01*
X165823Y1426553D01*
Y1428353D01*
G01X169023Y1536486D02*
X169490Y1536886D01*
X169756Y1537420D01*
X169823Y1538020D01*
X169756Y1538553D01*
X169423Y1539086D01*
X169023Y1539420D01*
X168623Y1539486D01*
X168156Y1539353D01*
X167823Y1538886D01*
X167690Y1538420D01*
Y1537820D01*
G01Y1538420D02*
X167490Y1538820D01*
X167156Y1539153D01*
X166756Y1539286D01*
X166356Y1539153D01*
X166023Y1538820D01*
X165823Y1538220D01*
X165890Y1537620D01*
X166156Y1537020D01*
G01X166490Y1541286D02*
X166090Y1541686D01*
X165890Y1542153D01*
X165823Y1542686D01*
X165956Y1543353D01*
X166290Y1543820D01*
X166690Y1543953D01*
X167090Y1543886D01*
X167423Y1543620D01*
X168090Y1542286D01*
X168556Y1541686D01*
X169223Y1541286D01*
X169823Y1541153D01*
Y1543953D01*
G01Y1545753D02*
X165823Y1548553D01*
G01Y1545753D02*
X169823Y1548553D01*
G01Y1551620D02*
X168956Y1551753D01*
X168223Y1551953D01*
X167556Y1552220D01*
X166823Y1552553D01*
X165823Y1553086D01*
Y1550420D01*
G01X169223Y1554886D02*
X169556Y1555286D01*
X169756Y1555753D01*
X169823Y1556353D01*
X169690Y1556953D01*
X169423Y1557420D01*
X168956Y1557753D01*
X168423Y1557820D01*
X167890Y1557686D01*
X167556Y1557353D01*
X167290Y1556886D01*
X167223Y1556420D01*
X167290Y1555953D01*
X167556Y1555353D01*
X165823Y1555553D01*
Y1557353D01*
G01X169023Y1812998D02*
X169490Y1813398D01*
X169756Y1813932D01*
X169823Y1814532D01*
X169756Y1815065D01*
X169423Y1815598D01*
X169023Y1815932D01*
X168623Y1815998D01*
X168156Y1815865D01*
X167823Y1815398D01*
X167690Y1814932D01*
Y1814332D01*
G01Y1814932D02*
X167490Y1815332D01*
X167156Y1815665D01*
X166756Y1815798D01*
X166356Y1815665D01*
X166023Y1815332D01*
X165823Y1814732D01*
X165890Y1814132D01*
X166156Y1813532D01*
G01X166490Y1817798D02*
X166090Y1818198D01*
X165890Y1818665D01*
X165823Y1819198D01*
X165956Y1819865D01*
X166290Y1820332D01*
X166690Y1820465D01*
X167090Y1820398D01*
X167423Y1820132D01*
X168090Y1818798D01*
X168556Y1818198D01*
X169223Y1817798D01*
X169823Y1817665D01*
Y1820465D01*
G01Y1822265D02*
X165823Y1825065D01*
G01Y1822265D02*
X169823Y1825065D01*
G01Y1828132D02*
X168956Y1828265D01*
X168223Y1828465D01*
X167556Y1828732D01*
X166823Y1829065D01*
X165823Y1829598D01*
Y1826932D01*
G01X169223Y1831398D02*
X169556Y1831798D01*
X169756Y1832265D01*
X169823Y1832865D01*
X169690Y1833465D01*
X169423Y1833932D01*
X168956Y1834265D01*
X168423Y1834332D01*
X167890Y1834198D01*
X167556Y1833865D01*
X167290Y1833398D01*
X167223Y1832932D01*
X167290Y1832465D01*
X167556Y1831865D01*
X165823Y1832065D01*
Y1833865D01*
G01X169023Y1941998D02*
X169490Y1942398D01*
X169756Y1942932D01*
X169823Y1943532D01*
X169756Y1944065D01*
X169423Y1944598D01*
X169023Y1944932D01*
X168623Y1944998D01*
X168156Y1944865D01*
X167823Y1944398D01*
X167690Y1943932D01*
Y1943332D01*
G01Y1943932D02*
X167490Y1944332D01*
X167156Y1944665D01*
X166756Y1944798D01*
X166356Y1944665D01*
X166023Y1944332D01*
X165823Y1943732D01*
X165890Y1943132D01*
X166156Y1942532D01*
G01X166490Y1946798D02*
X166090Y1947198D01*
X165890Y1947665D01*
X165823Y1948198D01*
X165956Y1948865D01*
X166290Y1949332D01*
X166690Y1949465D01*
X167090Y1949398D01*
X167423Y1949132D01*
X168090Y1947798D01*
X168556Y1947198D01*
X169223Y1946798D01*
X169823Y1946665D01*
Y1949465D01*
G01Y1951265D02*
X165823Y1954065D01*
G01Y1951265D02*
X169823Y1954065D01*
G01Y1957132D02*
X168956Y1957265D01*
X168223Y1957465D01*
X167556Y1957732D01*
X166823Y1958065D01*
X165823Y1958598D01*
Y1955932D01*
G01X169223Y1960398D02*
X169556Y1960798D01*
X169756Y1961265D01*
X169823Y1961865D01*
X169690Y1962465D01*
X169423Y1962932D01*
X168956Y1963265D01*
X168423Y1963332D01*
X167890Y1963198D01*
X167556Y1962865D01*
X167290Y1962398D01*
X167223Y1961932D01*
X167290Y1961465D01*
X167556Y1960865D01*
X165823Y1961065D01*
Y1962865D01*
G01X897369Y190950D02*
X897836Y191350D01*
X898102Y191884D01*
X898169Y192484D01*
X898102Y193017D01*
X897769Y193550D01*
X897369Y193884D01*
X896969Y193950D01*
X896502Y193817D01*
X896169Y193350D01*
X896036Y192884D01*
Y192284D01*
G01Y192884D02*
X895836Y193284D01*
X895502Y193617D01*
X895102Y193750D01*
X894702Y193617D01*
X894369Y193284D01*
X894169Y192684D01*
X894236Y192084D01*
X894502Y191484D01*
G01X894836Y195750D02*
X894436Y196150D01*
X894236Y196617D01*
X894169Y197150D01*
X894302Y197817D01*
X894636Y198284D01*
X895036Y198417D01*
X895436Y198350D01*
X895769Y198084D01*
X896436Y196750D01*
X896902Y196150D01*
X897569Y195750D01*
X898169Y195617D01*
Y198417D01*
G01Y200217D02*
X894169Y203017D01*
G01Y200217D02*
X898169Y203017D01*
G01Y206084D02*
X897302Y206217D01*
X896569Y206417D01*
X895902Y206684D01*
X895169Y207017D01*
X894169Y207550D01*
Y204884D01*
G01X897569Y209350D02*
X897902Y209750D01*
X898102Y210217D01*
X898169Y210817D01*
X898036Y211417D01*
X897769Y211884D01*
X897302Y212217D01*
X896769Y212284D01*
X896236Y212150D01*
X895902Y211817D01*
X895636Y211350D01*
X895569Y210884D01*
X895636Y210417D01*
X895902Y209817D01*
X894169Y210017D01*
Y211817D01*
G01X897369Y319950D02*
X897836Y320350D01*
X898102Y320884D01*
X898169Y321484D01*
X898102Y322017D01*
X897769Y322550D01*
X897369Y322884D01*
X896969Y322950D01*
X896502Y322817D01*
X896169Y322350D01*
X896036Y321884D01*
Y321284D01*
G01Y321884D02*
X895836Y322284D01*
X895502Y322617D01*
X895102Y322750D01*
X894702Y322617D01*
X894369Y322284D01*
X894169Y321684D01*
X894236Y321084D01*
X894502Y320484D01*
G01X894836Y324750D02*
X894436Y325150D01*
X894236Y325617D01*
X894169Y326150D01*
X894302Y326817D01*
X894636Y327284D01*
X895036Y327417D01*
X895436Y327350D01*
X895769Y327084D01*
X896436Y325750D01*
X896902Y325150D01*
X897569Y324750D01*
X898169Y324617D01*
Y327417D01*
G01Y329217D02*
X894169Y332017D01*
G01Y329217D02*
X898169Y332017D01*
G01Y335084D02*
X897302Y335217D01*
X896569Y335417D01*
X895902Y335684D01*
X895169Y336017D01*
X894169Y336550D01*
Y333884D01*
G01X897569Y338350D02*
X897902Y338750D01*
X898102Y339217D01*
X898169Y339817D01*
X898036Y340417D01*
X897769Y340884D01*
X897302Y341217D01*
X896769Y341284D01*
X896236Y341150D01*
X895902Y340817D01*
X895636Y340350D01*
X895569Y339884D01*
X895636Y339417D01*
X895902Y338817D01*
X894169Y339017D01*
Y340817D01*
G01X897369Y596462D02*
X897836Y596862D01*
X898102Y597396D01*
X898169Y597996D01*
X898102Y598529D01*
X897769Y599062D01*
X897369Y599396D01*
X896969Y599462D01*
X896502Y599329D01*
X896169Y598862D01*
X896036Y598396D01*
Y597796D01*
G01Y598396D02*
X895836Y598796D01*
X895502Y599129D01*
X895102Y599262D01*
X894702Y599129D01*
X894369Y598796D01*
X894169Y598196D01*
X894236Y597596D01*
X894502Y596996D01*
G01X894836Y601262D02*
X894436Y601662D01*
X894236Y602129D01*
X894169Y602662D01*
X894302Y603329D01*
X894636Y603796D01*
X895036Y603929D01*
X895436Y603862D01*
X895769Y603596D01*
X896436Y602262D01*
X896902Y601662D01*
X897569Y601262D01*
X898169Y601129D01*
Y603929D01*
G01Y605729D02*
X894169Y608529D01*
G01Y605729D02*
X898169Y608529D01*
G01Y611596D02*
X897302Y611729D01*
X896569Y611929D01*
X895902Y612196D01*
X895169Y612529D01*
X894169Y613062D01*
Y610396D01*
G01X897569Y614862D02*
X897902Y615262D01*
X898102Y615729D01*
X898169Y616329D01*
X898036Y616929D01*
X897769Y617396D01*
X897302Y617729D01*
X896769Y617796D01*
X896236Y617662D01*
X895902Y617329D01*
X895636Y616862D01*
X895569Y616396D01*
X895636Y615929D01*
X895902Y615329D01*
X894169Y615529D01*
Y617329D01*
G01X897369Y725462D02*
X897836Y725862D01*
X898102Y726396D01*
X898169Y726996D01*
X898102Y727529D01*
X897769Y728062D01*
X897369Y728396D01*
X896969Y728462D01*
X896502Y728329D01*
X896169Y727862D01*
X896036Y727396D01*
Y726796D01*
G01Y727396D02*
X895836Y727796D01*
X895502Y728129D01*
X895102Y728262D01*
X894702Y728129D01*
X894369Y727796D01*
X894169Y727196D01*
X894236Y726596D01*
X894502Y725996D01*
G01X894836Y730262D02*
X894436Y730662D01*
X894236Y731129D01*
X894169Y731662D01*
X894302Y732329D01*
X894636Y732796D01*
X895036Y732929D01*
X895436Y732862D01*
X895769Y732596D01*
X896436Y731262D01*
X896902Y730662D01*
X897569Y730262D01*
X898169Y730129D01*
Y732929D01*
G01Y734729D02*
X894169Y737529D01*
G01Y734729D02*
X898169Y737529D01*
G01Y740596D02*
X897302Y740729D01*
X896569Y740929D01*
X895902Y741196D01*
X895169Y741529D01*
X894169Y742062D01*
Y739396D01*
G01X897569Y743862D02*
X897902Y744262D01*
X898102Y744729D01*
X898169Y745329D01*
X898036Y745929D01*
X897769Y746396D01*
X897302Y746729D01*
X896769Y746796D01*
X896236Y746662D01*
X895902Y746329D01*
X895636Y745862D01*
X895569Y745396D01*
X895636Y744929D01*
X895902Y744329D01*
X894169Y744529D01*
Y746329D01*
G01X897369Y1001974D02*
X897836Y1002374D01*
X898102Y1002908D01*
X898169Y1003508D01*
X898102Y1004041D01*
X897769Y1004574D01*
X897369Y1004908D01*
X896969Y1004974D01*
X896502Y1004841D01*
X896169Y1004374D01*
X896036Y1003908D01*
Y1003308D01*
G01Y1003908D02*
X895836Y1004308D01*
X895502Y1004641D01*
X895102Y1004774D01*
X894702Y1004641D01*
X894369Y1004308D01*
X894169Y1003708D01*
X894236Y1003108D01*
X894502Y1002508D01*
G01X894836Y1006774D02*
X894436Y1007174D01*
X894236Y1007641D01*
X894169Y1008174D01*
X894302Y1008841D01*
X894636Y1009308D01*
X895036Y1009441D01*
X895436Y1009374D01*
X895769Y1009108D01*
X896436Y1007774D01*
X896902Y1007174D01*
X897569Y1006774D01*
X898169Y1006641D01*
Y1009441D01*
G01Y1011241D02*
X894169Y1014041D01*
G01Y1011241D02*
X898169Y1014041D01*
G01Y1017108D02*
X897302Y1017241D01*
X896569Y1017441D01*
X895902Y1017708D01*
X895169Y1018041D01*
X894169Y1018574D01*
Y1015908D01*
G01X897569Y1020374D02*
X897902Y1020774D01*
X898102Y1021241D01*
X898169Y1021841D01*
X898036Y1022441D01*
X897769Y1022908D01*
X897302Y1023241D01*
X896769Y1023308D01*
X896236Y1023174D01*
X895902Y1022841D01*
X895636Y1022374D01*
X895569Y1021908D01*
X895636Y1021441D01*
X895902Y1020841D01*
X894169Y1021041D01*
Y1022841D01*
G01X897369Y1130974D02*
X897836Y1131374D01*
X898102Y1131908D01*
X898169Y1132508D01*
X898102Y1133041D01*
X897769Y1133574D01*
X897369Y1133908D01*
X896969Y1133974D01*
X896502Y1133841D01*
X896169Y1133374D01*
X896036Y1132908D01*
Y1132308D01*
G01Y1132908D02*
X895836Y1133308D01*
X895502Y1133641D01*
X895102Y1133774D01*
X894702Y1133641D01*
X894369Y1133308D01*
X894169Y1132708D01*
X894236Y1132108D01*
X894502Y1131508D01*
G01X894836Y1135774D02*
X894436Y1136174D01*
X894236Y1136641D01*
X894169Y1137174D01*
X894302Y1137841D01*
X894636Y1138308D01*
X895036Y1138441D01*
X895436Y1138374D01*
X895769Y1138108D01*
X896436Y1136774D01*
X896902Y1136174D01*
X897569Y1135774D01*
X898169Y1135641D01*
Y1138441D01*
G01Y1140241D02*
X894169Y1143041D01*
G01Y1140241D02*
X898169Y1143041D01*
G01Y1146108D02*
X897302Y1146241D01*
X896569Y1146441D01*
X895902Y1146708D01*
X895169Y1147041D01*
X894169Y1147574D01*
Y1144908D01*
G01X897569Y1149374D02*
X897902Y1149774D01*
X898102Y1150241D01*
X898169Y1150841D01*
X898036Y1151441D01*
X897769Y1151908D01*
X897302Y1152241D01*
X896769Y1152308D01*
X896236Y1152174D01*
X895902Y1151841D01*
X895636Y1151374D01*
X895569Y1150908D01*
X895636Y1150441D01*
X895902Y1149841D01*
X894169Y1150041D01*
Y1151841D01*
G01X897369Y1407486D02*
X897836Y1407886D01*
X898102Y1408420D01*
X898169Y1409020D01*
X898102Y1409553D01*
X897769Y1410086D01*
X897369Y1410420D01*
X896969Y1410486D01*
X896502Y1410353D01*
X896169Y1409886D01*
X896036Y1409420D01*
Y1408820D01*
G01Y1409420D02*
X895836Y1409820D01*
X895502Y1410153D01*
X895102Y1410286D01*
X894702Y1410153D01*
X894369Y1409820D01*
X894169Y1409220D01*
X894236Y1408620D01*
X894502Y1408020D01*
G01X894836Y1412286D02*
X894436Y1412686D01*
X894236Y1413153D01*
X894169Y1413686D01*
X894302Y1414353D01*
X894636Y1414820D01*
X895036Y1414953D01*
X895436Y1414886D01*
X895769Y1414620D01*
X896436Y1413286D01*
X896902Y1412686D01*
X897569Y1412286D01*
X898169Y1412153D01*
Y1414953D01*
G01Y1416753D02*
X894169Y1419553D01*
G01Y1416753D02*
X898169Y1419553D01*
G01Y1422620D02*
X897302Y1422753D01*
X896569Y1422953D01*
X895902Y1423220D01*
X895169Y1423553D01*
X894169Y1424086D01*
Y1421420D01*
G01X897569Y1425886D02*
X897902Y1426286D01*
X898102Y1426753D01*
X898169Y1427353D01*
X898036Y1427953D01*
X897769Y1428420D01*
X897302Y1428753D01*
X896769Y1428820D01*
X896236Y1428686D01*
X895902Y1428353D01*
X895636Y1427886D01*
X895569Y1427420D01*
X895636Y1426953D01*
X895902Y1426353D01*
X894169Y1426553D01*
Y1428353D01*
G01X897369Y1536486D02*
X897836Y1536886D01*
X898102Y1537420D01*
X898169Y1538020D01*
X898102Y1538553D01*
X897769Y1539086D01*
X897369Y1539420D01*
X896969Y1539486D01*
X896502Y1539353D01*
X896169Y1538886D01*
X896036Y1538420D01*
Y1537820D01*
G01Y1538420D02*
X895836Y1538820D01*
X895502Y1539153D01*
X895102Y1539286D01*
X894702Y1539153D01*
X894369Y1538820D01*
X894169Y1538220D01*
X894236Y1537620D01*
X894502Y1537020D01*
G01X894836Y1541286D02*
X894436Y1541686D01*
X894236Y1542153D01*
X894169Y1542686D01*
X894302Y1543353D01*
X894636Y1543820D01*
X895036Y1543953D01*
X895436Y1543886D01*
X895769Y1543620D01*
X896436Y1542286D01*
X896902Y1541686D01*
X897569Y1541286D01*
X898169Y1541153D01*
Y1543953D01*
G01Y1545753D02*
X894169Y1548553D01*
G01Y1545753D02*
X898169Y1548553D01*
G01Y1551620D02*
X897302Y1551753D01*
X896569Y1551953D01*
X895902Y1552220D01*
X895169Y1552553D01*
X894169Y1553086D01*
Y1550420D01*
G01X897569Y1554886D02*
X897902Y1555286D01*
X898102Y1555753D01*
X898169Y1556353D01*
X898036Y1556953D01*
X897769Y1557420D01*
X897302Y1557753D01*
X896769Y1557820D01*
X896236Y1557686D01*
X895902Y1557353D01*
X895636Y1556886D01*
X895569Y1556420D01*
X895636Y1555953D01*
X895902Y1555353D01*
X894169Y1555553D01*
Y1557353D01*
G01X897369Y1812998D02*
X897836Y1813398D01*
X898102Y1813932D01*
X898169Y1814532D01*
X898102Y1815065D01*
X897769Y1815598D01*
X897369Y1815932D01*
X896969Y1815998D01*
X896502Y1815865D01*
X896169Y1815398D01*
X896036Y1814932D01*
Y1814332D01*
G01Y1814932D02*
X895836Y1815332D01*
X895502Y1815665D01*
X895102Y1815798D01*
X894702Y1815665D01*
X894369Y1815332D01*
X894169Y1814732D01*
X894236Y1814132D01*
X894502Y1813532D01*
G01X894836Y1817798D02*
X894436Y1818198D01*
X894236Y1818665D01*
X894169Y1819198D01*
X894302Y1819865D01*
X894636Y1820332D01*
X895036Y1820465D01*
X895436Y1820398D01*
X895769Y1820132D01*
X896436Y1818798D01*
X896902Y1818198D01*
X897569Y1817798D01*
X898169Y1817665D01*
Y1820465D01*
G01Y1822265D02*
X894169Y1825065D01*
G01Y1822265D02*
X898169Y1825065D01*
G01Y1828132D02*
X897302Y1828265D01*
X896569Y1828465D01*
X895902Y1828732D01*
X895169Y1829065D01*
X894169Y1829598D01*
Y1826932D01*
G01X897569Y1831398D02*
X897902Y1831798D01*
X898102Y1832265D01*
X898169Y1832865D01*
X898036Y1833465D01*
X897769Y1833932D01*
X897302Y1834265D01*
X896769Y1834332D01*
X896236Y1834198D01*
X895902Y1833865D01*
X895636Y1833398D01*
X895569Y1832932D01*
X895636Y1832465D01*
X895902Y1831865D01*
X894169Y1832065D01*
Y1833865D01*
G01X897369Y1941998D02*
X897836Y1942398D01*
X898102Y1942932D01*
X898169Y1943532D01*
X898102Y1944065D01*
X897769Y1944598D01*
X897369Y1944932D01*
X896969Y1944998D01*
X896502Y1944865D01*
X896169Y1944398D01*
X896036Y1943932D01*
Y1943332D01*
G01Y1943932D02*
X895836Y1944332D01*
X895502Y1944665D01*
X895102Y1944798D01*
X894702Y1944665D01*
X894369Y1944332D01*
X894169Y1943732D01*
X894236Y1943132D01*
X894502Y1942532D01*
G01X894836Y1946798D02*
X894436Y1947198D01*
X894236Y1947665D01*
X894169Y1948198D01*
X894302Y1948865D01*
X894636Y1949332D01*
X895036Y1949465D01*
X895436Y1949398D01*
X895769Y1949132D01*
X896436Y1947798D01*
X896902Y1947198D01*
X897569Y1946798D01*
X898169Y1946665D01*
Y1949465D01*
G01Y1951265D02*
X894169Y1954065D01*
G01Y1951265D02*
X898169Y1954065D01*
G01Y1957132D02*
X897302Y1957265D01*
X896569Y1957465D01*
X895902Y1957732D01*
X895169Y1958065D01*
X894169Y1958598D01*
Y1955932D01*
G01X897569Y1960398D02*
X897902Y1960798D01*
X898102Y1961265D01*
X898169Y1961865D01*
X898036Y1962465D01*
X897769Y1962932D01*
X897302Y1963265D01*
X896769Y1963332D01*
X896236Y1963198D01*
X895902Y1962865D01*
X895636Y1962398D01*
X895569Y1961932D01*
X895636Y1961465D01*
X895902Y1960865D01*
X894169Y1961065D01*
Y1962865D01*
G01X1033464Y1397976D02*
Y1424882D01*
X1029527Y1428819D01*
X1024212D01*
G02X1019291Y1433740I0J4921D01*
G01Y1610886D01*
X1018307Y1611870D01*
X989744D01*
G02Y1616082I0J2106D01*
G01X1018307D01*
X1019291Y1617066D01*
Y1676496D01*
G02X1024212Y1681417I4921J0D01*
G01X1029527D01*
X1033464Y1685354D01*
Y1712976D01*
G01X1019816Y1553876D02*
X1035791Y1553976D01*
G01X1024807Y1555407D02*
X1019816Y1553876D01*
X1024825Y1552407D01*
X1024807Y1555407D01*
G01X1038808Y1545726D02*
X1039141Y1546259D01*
X1039341Y1546859D01*
Y1547393D01*
X1039141Y1547926D01*
X1038808Y1548326D01*
X1038341Y1548526D01*
X1037874Y1548393D01*
X1037474Y1548059D01*
X1037208Y1547459D01*
X1037074Y1546659D01*
X1036808Y1546193D01*
X1036341Y1545993D01*
X1035874Y1546126D01*
X1035541Y1546459D01*
X1035341Y1546926D01*
Y1547393D01*
X1035474Y1547859D01*
X1035808Y1548259D01*
G01X1039341Y1551726D02*
X1035341D01*
G01X1036674Y1556326D02*
X1039341D01*
G01X1035608D02*
X1035541Y1556193D01*
X1035408D01*
X1035341Y1556326D01*
X1035408Y1556459D01*
X1035541D01*
X1035608Y1556326D01*
G01X1035341Y1560926D02*
X1039341D01*
G01X1036674Y1559993D02*
Y1561859D01*
G54D12*
X29531Y309549D03*
Y1029510D03*
X17720Y1903132D03*
X271657Y267699D03*
Y673210D03*
Y1078722D03*
Y1484234D03*
Y1889746D03*
X994098Y149588D03*
Y673210D03*
Y1068880D03*
X1234250Y1657850D03*
G54D13*
X9843Y353144D03*
Y717711D03*
Y762617D03*
Y875216D03*
Y1337396D03*
Y1701963D03*
Y1746869D03*
Y1859468D03*
X1234250Y1545450D03*
G54D14*
X14999Y1936050D03*
Y1940050D03*
X8499Y1937550D03*
X15099Y1944050D03*
X5303Y1947050D03*
X11703Y1951946D03*
X17499Y1961050D03*
X29699Y388484D03*
X29599Y382884D03*
X23399Y373931D03*
Y389679D03*
X23499Y381831D03*
X26299Y383854D03*
Y387629D03*
X28100Y374000D03*
X26299Y399601D03*
Y403376D03*
X29999Y398684D03*
X29899Y404384D03*
X23799Y405684D03*
X23499Y397579D03*
X35900Y412600D03*
X26524Y426720D03*
X26399Y423322D03*
X28672Y429356D03*
X29365Y421169D03*
X23399Y429051D03*
X28900Y417800D03*
X26492Y439350D03*
X26599Y442749D03*
X26899Y454850D03*
X28700Y451900D03*
X28800Y436700D03*
X28700Y445700D03*
X23399Y444799D03*
X23499Y452699D03*
Y436951D03*
X26799Y458497D03*
X26486Y462648D03*
X26499Y466250D03*
X29500Y460800D03*
X23499Y468447D03*
X23399Y476295D03*
Y460547D03*
X26299Y478404D03*
X26515Y481798D03*
X23399Y492043D03*
X23499Y484195D03*
X36499Y517775D03*
X26399Y501966D03*
Y505741D03*
X28600Y508500D03*
X38400Y514955D03*
X28664Y499429D03*
X23499Y515691D03*
Y499943D03*
X23399Y507791D03*
X36499Y521550D03*
X35338Y524746D03*
X26691Y532701D03*
X22800Y539600D03*
X23399Y523539D03*
X23499Y531439D03*
X26599Y525648D03*
Y529302D03*
X27199Y539600D03*
X39217Y554750D03*
X33307Y557938D03*
X26199Y547176D03*
X29999Y557150D03*
X33699Y561850D03*
X36499Y566350D03*
X22699Y577950D03*
X22999Y565550D03*
X28000Y578500D03*
X25581Y567763D03*
X27699Y573750D03*
X22978Y588571D03*
X28808Y593150D03*
X28700Y596549D03*
X27499Y620203D03*
Y623857D03*
X37999Y611550D03*
X26869Y616861D03*
X23499Y618053D03*
X23999Y609250D03*
X34976Y619250D03*
X26800Y611500D03*
X32200Y603710D03*
X31598Y607102D03*
X39600Y626984D03*
X38300Y633800D03*
X30712Y624971D03*
X29999Y640550D03*
X29819Y634951D03*
X23399Y641649D03*
X23799Y625950D03*
X23499Y633801D03*
X26568Y635950D03*
Y639604D03*
X30999Y656250D03*
Y650550D03*
X23499Y665297D03*
Y649549D03*
X23725Y657471D03*
X26737Y651957D03*
X26999Y656550D03*
X23699Y673150D03*
X23499Y681045D03*
X27687Y667447D03*
Y671101D03*
X27700Y682700D03*
X29999Y694550D03*
X25999Y694870D03*
X23999Y689050D03*
X27299Y783550D03*
X35300Y789375D03*
X32800Y803050D03*
X37416Y799033D03*
X37099Y811350D03*
X26299Y815050D03*
X35559Y795112D03*
X31699Y814350D03*
X37216Y807951D03*
X39649Y822000D03*
X29299Y836901D03*
X40400Y840792D03*
X22500Y853700D03*
X29600Y854000D03*
X23299Y863050D03*
X26662Y861550D03*
X25000Y858100D03*
X20400Y1048300D03*
X20999Y1320550D03*
X23700Y1354600D03*
X20999Y1352050D03*
X25000Y1357742D03*
X22851Y1374169D03*
X22999Y1366050D03*
X23499Y1381550D03*
X25507Y1372045D03*
X25558Y1368447D03*
X32550Y1392777D03*
X27499Y1387550D03*
X24499Y1389663D03*
X28499Y1391050D03*
X32333Y1389383D03*
X30500Y1395500D03*
X33321Y1414755D03*
X29786Y1414858D03*
X23499Y1421550D03*
X23999Y1413550D03*
X32451Y1411468D03*
X28999Y1411550D03*
X32094Y1448448D03*
X28697Y1448296D03*
X36198Y1446749D03*
X27099Y1444350D03*
X30999Y1438050D03*
X27999Y1430050D03*
X23499Y1445050D03*
X22999Y1437050D03*
X23999Y1429050D03*
X33206Y1432352D03*
X30499Y1434550D03*
X30378Y1462518D03*
X33915Y1462681D03*
X29069Y1459379D03*
X36791Y1460866D03*
X23028Y1468579D03*
X23499Y1460550D03*
X22999Y1453050D03*
X34465Y1481683D03*
X30999Y1482050D03*
X32520Y1485092D03*
X28999Y1478050D03*
X23599Y1476350D03*
X23277Y1484050D03*
X34099Y1497550D03*
X30499D03*
X27499Y1495050D03*
X36999Y1494550D03*
X22999Y1500050D03*
X23799Y1508050D03*
X24499Y1492050D03*
X30115Y1511900D03*
X33512Y1512051D03*
X29631Y1533063D03*
X31999Y1517846D03*
Y1521500D03*
X35245Y1522512D03*
X35999Y1514550D03*
X29765Y1515282D03*
X24423Y1527123D03*
X22999Y1515550D03*
X37999Y1530900D03*
X24199Y1523700D03*
X25247Y1546912D03*
X38500Y1534600D03*
X32099Y1535550D03*
X26705Y1534795D03*
X30199Y1545450D03*
X36340Y1558809D03*
X34896Y1555730D03*
X38208Y1569841D03*
X25521Y1563350D03*
X30520Y1572049D03*
X24999Y1569550D03*
X31149Y1568300D03*
X23608Y1572653D03*
X24323Y1559950D03*
X27123Y1572205D03*
X39000Y1573500D03*
X34999Y1595350D03*
X22699Y1594224D03*
X31099Y1595350D03*
X28899Y1613524D03*
X32299D03*
X26999Y1610550D03*
X34884Y1615734D03*
X23499Y1618050D03*
Y1610050D03*
Y1602050D03*
X33599Y1600200D03*
X29499Y1630050D03*
X32199Y1633124D03*
X34816Y1630953D03*
X22999Y1626050D03*
X23499Y1634050D03*
X32663Y1628181D03*
X31999Y1661127D03*
X28600Y1661039D03*
X29626Y1645002D03*
X33026Y1645051D03*
X27499Y1657050D03*
X32989Y1648451D03*
X26785Y1642089D03*
X23499Y1657050D03*
X23999Y1649550D03*
X23415Y1641634D03*
X34699Y1663300D03*
X22999Y1665550D03*
X24244Y1681868D03*
X22864Y1673550D03*
X32700Y1673300D03*
X32494Y1669706D03*
X29100Y1669500D03*
X30500Y1697500D03*
X39900Y1751200D03*
X41200Y1747050D03*
X30274Y1787238D03*
X35675Y1783450D03*
X39324Y1780623D03*
X38094Y1785840D03*
X38878Y1799571D03*
X34599Y1805123D03*
X37699Y1789850D03*
X37574Y1794050D03*
X31811Y1790271D03*
X40478Y1795820D03*
X32099Y1797150D03*
X28550Y1828153D03*
X29899Y1821050D03*
X34099Y1822850D03*
X35876Y1812350D03*
X34129Y1815267D03*
X36532Y1825352D03*
X36399Y1828750D03*
X26099Y1824950D03*
X29599Y1844350D03*
X22099Y1836609D03*
X28123Y1831527D03*
X25999Y1842550D03*
X39699Y1833850D03*
X28799Y1919060D03*
X23030Y1922038D03*
X26765Y1921945D03*
X34799Y1946750D03*
X38703Y1946754D03*
X25499Y1956050D03*
X32999Y1960555D03*
X31799Y1979050D03*
X41999Y200050D03*
X45800Y405200D03*
X61400Y452600D03*
X62497Y474346D03*
X60003Y534150D03*
X59999Y537550D03*
X42867Y548450D03*
X43099Y555850D03*
X46299Y552950D03*
X49799Y559150D03*
X42599Y567850D03*
X47543Y578340D03*
X44959Y575756D03*
X60076Y595777D03*
X55499Y595650D03*
X42202Y608195D03*
X41400Y611500D03*
X47626Y611300D03*
X45701Y607700D03*
X42709Y625607D03*
X41500Y642800D03*
X57800Y634300D03*
X44900Y642800D03*
X47101Y632355D03*
X41500Y635000D03*
X52500D03*
X48999Y642900D03*
X50410Y695801D03*
X50300Y699200D03*
X45100Y793100D03*
X44046Y799554D03*
X46887Y803413D03*
X51100Y806300D03*
X49900Y813200D03*
X56281Y801350D03*
X50399Y836250D03*
X46700Y820100D03*
X54074Y815750D03*
X62405Y820300D03*
X46576Y832951D03*
X48346Y844529D03*
X58699Y837250D03*
X44697Y1546793D03*
X44299Y1550950D03*
X42199Y1601050D03*
X47400Y1721700D03*
X42000Y1740100D03*
X47717Y1731337D03*
X47800Y1740500D03*
X45877Y1728477D03*
Y1724823D03*
X47000Y1737100D03*
X43600D03*
X42275Y1754000D03*
X45799Y1757650D03*
X47440Y1761391D03*
X47400Y1765250D03*
X43751Y1780559D03*
X46999Y1779550D03*
X46199Y1783050D03*
X43925Y1767890D03*
X47604Y1769005D03*
X45782Y1771877D03*
X47499Y1775350D03*
X47899Y1798650D03*
X48049Y1791450D03*
X42199Y1792250D03*
X46799Y1794900D03*
X61009Y1822340D03*
X60449Y1842550D03*
X46499Y1836550D03*
X47166Y1839884D03*
X43099Y1833850D03*
X57999Y1891050D03*
X42499Y1902550D03*
X48499Y1897050D03*
X44368Y1951450D03*
X44399Y1942250D03*
X42532Y1946783D03*
X53999Y1946650D03*
X50299D03*
X46565Y1946703D03*
X45999Y1971450D03*
X50499Y1961550D03*
X43462Y1961160D03*
X78700Y74200D03*
Y70700D03*
X74999Y70550D03*
Y74050D03*
X74499Y80650D03*
Y84050D03*
X65999Y216050D03*
X65000Y455500D03*
X62503Y470946D03*
X66199Y475184D03*
Y469884D03*
X77499Y469550D03*
X62978Y486217D03*
X63067Y489616D03*
X66299Y490784D03*
Y485484D03*
X77999Y493050D03*
X77499Y502550D03*
X65599Y514250D03*
X63499Y538550D03*
Y533050D03*
X68000Y546500D03*
X72500Y545000D03*
X81251Y607249D03*
Y619251D03*
X82499Y627050D03*
X80499Y664550D03*
X74499Y662050D03*
X78499Y654050D03*
X76999Y664550D03*
X81999Y668050D03*
X65500Y817700D03*
X80500Y817000D03*
X76540Y850938D03*
X75500Y847700D03*
X68860Y838706D03*
X69499Y842950D03*
X63499Y843050D03*
X74220Y854150D03*
X72362Y849550D03*
X80699Y1004450D03*
Y1000450D03*
X72000Y1013400D03*
X63273Y1023974D03*
X66499Y1025050D03*
X75500Y1012261D03*
X65486Y1031515D03*
X80000Y1090500D03*
X74500Y1097550D03*
X79899Y1104550D03*
X74399Y1111550D03*
X76999Y1196550D03*
X78499Y1273550D03*
X78613Y1282664D03*
X78779Y1302664D03*
Y1312664D03*
X77758Y1357742D03*
X76000Y1431100D03*
X80043Y1544691D03*
X78600Y1561900D03*
X75000Y1561800D03*
X74400Y1574800D03*
X80400Y1571766D03*
X82329Y1568117D03*
X79000Y1555500D03*
X82429D03*
X74800Y1584700D03*
X78100Y1688189D03*
X74500Y1692000D03*
X74400Y1778100D03*
X80099Y1817250D03*
X80999Y1836550D03*
X93999Y58550D03*
X92900Y66128D03*
X92999Y86128D03*
X97499Y90050D03*
X92999Y96128D03*
X89603Y132629D03*
X86899Y130567D03*
X86599Y126750D03*
X95350Y204550D03*
X89800Y208550D03*
X96900Y510000D03*
X93200Y510500D03*
X95500Y513400D03*
X98900D03*
X83700Y529500D03*
X88999Y538050D03*
X104502Y530552D03*
X86199Y536025D03*
Y532250D03*
X89000Y816500D03*
X90000Y826000D03*
X90500Y831500D03*
X98700Y822550D03*
X98000Y833500D03*
X98700Y842600D03*
X92999Y868550D03*
X92499Y876550D03*
X94999Y901550D03*
X89469Y935588D03*
X85999Y940429D03*
X86399Y937050D03*
X89499Y942850D03*
X102100Y968500D03*
X99000Y965000D03*
X104600Y980500D03*
X90000Y993100D03*
X92600Y996100D03*
X88000Y1008500D03*
X101499Y1072550D03*
X103999Y1216863D03*
X102900Y1196050D03*
X103686Y1223863D03*
X101541Y1262607D03*
X101399Y1292550D03*
X102700Y1321363D03*
X102000Y1341000D03*
X91279Y1340642D03*
X86165Y1339050D03*
X86890Y1342860D03*
X101500Y1352000D03*
X89999Y1348050D03*
X86890Y1346635D03*
X102350Y1344500D03*
Y1348154D03*
X97229Y1373337D03*
X97000Y1377600D03*
X98599Y1491350D03*
X100699Y1471050D03*
X100499Y1479650D03*
X83932Y1544705D03*
X100800Y1536450D03*
X96200Y1550100D03*
X99899Y1539850D03*
X100000Y1546650D03*
X90324Y1538800D03*
X97499Y1554550D03*
X98144Y1534309D03*
X96999Y1558050D03*
X89373Y1561073D03*
X85600Y1561500D03*
X95499Y1665418D03*
X92900Y1678176D03*
X93999Y1703050D03*
X92873Y1708176D03*
X92479Y1718176D03*
X89306Y1746856D03*
X89499Y1753575D03*
X85341Y1752245D03*
X85194Y1748848D03*
X99199Y1761899D03*
X99999Y1753575D03*
X101399Y1784700D03*
X85599Y1797350D03*
X96600Y1826000D03*
X86649Y1817100D03*
X90000Y1827900D03*
X93500D03*
X97999Y1843050D03*
X112999Y124050D03*
X111790Y132259D03*
X115876Y125973D03*
Y130050D03*
X114900Y177900D03*
X122397Y252688D03*
X122799Y249150D03*
X124999Y246050D03*
X123378Y255944D03*
X107499Y497050D03*
X107526Y528996D03*
X109400Y543200D03*
X106000D03*
X105100Y600000D03*
X107000Y604800D03*
X125499Y635550D03*
Y638950D03*
X124999Y643050D03*
X110500Y790200D03*
X111100Y813400D03*
X111200Y799450D03*
X111207Y810001D03*
X110700Y795700D03*
X111089Y806603D03*
X110800Y803100D03*
X110499Y834550D03*
X106749Y934367D03*
X108441Y924705D03*
X108845Y931657D03*
X109099Y928250D03*
X108200Y963600D03*
X107300Y986000D03*
X107400Y992900D03*
X124100Y1047100D03*
X123999Y1054050D03*
Y1050650D03*
X120100Y1053200D03*
X116700Y1063500D03*
X112699Y1058974D03*
X105499Y1080550D03*
X106718Y1076050D03*
X105999Y1085800D03*
X121500Y1083600D03*
X121100Y1075300D03*
X117499Y1079300D03*
X105600Y1069500D03*
X124423Y1077523D03*
Y1081177D03*
X120749Y1093990D03*
X125900Y1091282D03*
X116249Y1102550D03*
X112999Y1103740D03*
X123999Y1102550D03*
X108999Y1102050D03*
X106999Y1194550D03*
X106162Y1205702D03*
X114999Y1210363D03*
X118999Y1219050D03*
X123970Y1221573D03*
X119399Y1298113D03*
X116999Y1288050D03*
X120507Y1317050D03*
X111499Y1311800D03*
X107999Y1307713D03*
X116499Y1328013D03*
X120507Y1328096D03*
X113000Y1341000D03*
X107228Y1330552D03*
X107500Y1340500D03*
X109228Y1337090D03*
Y1333315D03*
X119499Y1339050D03*
X113500Y1352000D03*
X110499Y1365050D03*
X109999Y1355050D03*
X112440Y1358196D03*
X112999Y1361550D03*
X121000Y1364000D03*
X113500Y1344500D03*
Y1348154D03*
X125100Y1366000D03*
X117390Y1426201D03*
X119507Y1423540D03*
X117390Y1429976D03*
X104935Y1440634D03*
X104999Y1444941D03*
X107328Y1438218D03*
X114499Y1432050D03*
X107999Y1448050D03*
X124290Y1469241D03*
X123808Y1465050D03*
X106999Y1454450D03*
X105099Y1459150D03*
X123999Y1473050D03*
X122199Y1476050D03*
X118499Y1694050D03*
X117499Y1706050D03*
X109499Y1712213D03*
X104999Y1708963D03*
X117249Y1712090D03*
X112753Y1716613D03*
X122642Y1704243D03*
X112562Y1720613D03*
X123749Y1711550D03*
X109499Y1743550D03*
X107499Y1736550D03*
X109399Y1739550D03*
X106999Y1746290D03*
X110099Y1759875D03*
X123393Y1870859D03*
X123592Y1874254D03*
X127999Y157050D03*
X147099Y245350D03*
X141499Y427550D03*
Y423050D03*
X135499Y517550D03*
X138999Y524213D03*
X137899Y545451D03*
X138416Y553500D03*
X140940Y561800D03*
X141300Y565900D03*
X127999Y645550D03*
X131400Y644600D03*
X144238Y645356D03*
X128725Y636626D03*
X128479Y640589D03*
X141773Y643013D03*
X144238Y649131D03*
X140499Y649350D03*
X134300Y646400D03*
X141500Y711000D03*
X137100Y1084800D03*
X140800Y1076300D03*
X137481Y1077557D03*
X137477Y1081177D03*
X132499Y1094550D03*
X138600Y1124600D03*
X130699Y1210653D03*
X135850Y1322250D03*
X125999Y1315550D03*
X132999Y1319550D03*
X142667Y1319218D03*
X143700Y1332500D03*
X133475Y1331200D03*
X140000Y1332600D03*
X138000Y1359025D03*
X129000Y1356500D03*
X142999Y1456373D03*
X139815Y1454438D03*
X139235Y1460973D03*
X127898Y1462441D03*
X142900Y1460000D03*
X133090Y1699959D03*
X128749Y1703300D03*
X131999Y1710050D03*
X141500Y1715500D03*
X135499Y1710150D03*
X141999Y1764550D03*
X137999Y1861497D03*
Y1865151D03*
X141101Y1866545D03*
X140999Y1859550D03*
X135999Y1881550D03*
X152499Y149550D03*
X154200Y168500D03*
X149400Y166400D03*
X149999Y243504D03*
Y239729D03*
X157440Y283924D03*
Y303924D03*
Y313924D03*
X165699Y428050D03*
X153459Y427494D03*
X154101Y445550D03*
X159600Y446399D03*
X163549Y517100D03*
X152000Y520813D03*
X163449Y521650D03*
X149000Y537500D03*
X150500Y545000D03*
X160932Y549468D03*
X150750Y540416D03*
X156500Y554000D03*
X157000Y573851D03*
X160824Y577000D03*
X161000Y639100D03*
X158885Y679436D03*
Y689436D03*
X158385Y719436D03*
X159500Y814700D03*
X165499Y815550D03*
X153500Y834600D03*
X154799Y838050D03*
X153499Y918550D03*
X163500Y937100D03*
X160399Y922850D03*
X152500Y960000D03*
X154749Y979149D03*
Y968249D03*
X164700Y1085400D03*
X159000Y1083000D03*
X157700Y1114948D03*
X157600Y1124948D03*
X149562Y1315987D03*
X147400Y1321600D03*
X148024Y1333525D03*
X150338Y1453958D03*
X152499Y1462940D03*
X157440Y1490460D03*
Y1500460D03*
Y1520460D03*
Y1530460D03*
X157400Y1596550D03*
X160200Y1598500D03*
X165575Y1676975D03*
X152633Y1677967D03*
X150999Y1713550D03*
X165900Y1790500D03*
X161900Y1793400D03*
X159421Y1925972D03*
X175999Y82428D03*
X174999Y79050D03*
X175499Y86572D03*
X176399Y94872D03*
X178999Y79050D03*
X186999Y99050D03*
X169999Y129050D03*
X188999Y120800D03*
X173499Y149050D03*
X173500Y166315D03*
X187699Y492850D03*
X173100Y483100D03*
X172499Y491053D03*
X176799Y493850D03*
X188000Y484500D03*
X171722Y513827D03*
X182499Y532550D03*
X168453Y527949D03*
X183499Y556100D03*
X172660Y815731D03*
X169106Y815865D03*
X174199Y841050D03*
X172500Y919294D03*
X172000Y931600D03*
X171100Y935000D03*
X171000Y939500D03*
X172000Y961000D03*
X170250Y948500D03*
X179499Y1275550D03*
X181000Y1365500D03*
X180500Y1369900D03*
X179999Y1655887D03*
X171999Y1662250D03*
X169600Y1682300D03*
X169100Y1685800D03*
X174250Y1694500D03*
X181100Y1682700D03*
X177900Y1690400D03*
X205938Y72528D03*
X201499Y104550D03*
X205499Y105550D03*
X207999Y109550D03*
X197899Y165075D03*
X199900Y554050D03*
X193549Y575875D03*
X200000Y818000D03*
X200539Y890300D03*
X200799Y896600D03*
X198924Y975975D03*
X199149Y1362900D03*
X194700Y1385700D03*
X193500Y1647000D03*
X201499Y1781050D03*
X194049Y1792600D03*
X210605Y70692D03*
X210685Y74725D03*
X215138Y72559D03*
X210634Y66863D03*
X210638Y62959D03*
X225499Y68550D03*
X210738Y82159D03*
Y78459D03*
X230749Y76300D03*
X213499Y104650D03*
X223499Y108150D03*
X218499Y190550D03*
X225298Y281114D03*
X213499Y283864D03*
X214063Y318114D03*
X213400Y355300D03*
X224998Y357049D03*
X220000Y516400D03*
X216999Y686550D03*
X213999Y725050D03*
X230849Y726050D03*
X228999Y765550D03*
X218224Y765325D03*
X211750Y894600D03*
X229562Y904113D03*
X215499Y905550D03*
X221800Y1069300D03*
X221300Y1083238D03*
X229800Y1073600D03*
X226800Y1093400D03*
X224750Y1483950D03*
X229025Y1471576D03*
X227814Y1887513D03*
X223436Y1890465D03*
X229800Y1875700D03*
X218100Y1886400D03*
X214999Y1909550D03*
X213562Y1926113D03*
X220062Y1931113D03*
X213138Y1952703D03*
X210999Y1942050D03*
X246999Y51550D03*
X246499Y42550D03*
X246999Y69550D03*
Y60550D03*
X246499Y86050D03*
Y80550D03*
X245499Y100550D03*
X233749Y110800D03*
X237899Y107050D03*
X247800Y269700D03*
X250300Y275100D03*
X250400Y283100D03*
X239600Y278600D03*
X231800Y318414D03*
X233998Y357549D03*
X239400Y357400D03*
X246800Y677100D03*
X249700Y682500D03*
X238500Y680800D03*
X249800Y689900D03*
X252499Y726050D03*
X241600Y765700D03*
X236800Y765800D03*
X233500Y1066100D03*
X242000Y1066000D03*
X247500Y1085500D03*
X251500Y1136700D03*
X241000Y1469600D03*
X233700Y1481600D03*
X232650Y1493450D03*
X231800Y1887100D03*
X232314Y1890513D03*
X236225Y1883125D03*
X231999Y1914050D03*
X249600Y1896800D03*
X249499Y1928050D03*
X240964Y1934113D03*
X253999Y44050D03*
X253871Y291410D03*
X252935Y319114D03*
X254499Y697700D03*
X255000Y1125700D03*
X256000Y1133000D03*
X269500Y1135500D03*
X261999Y1516050D03*
X257499Y1911050D03*
X264499Y1964050D03*
X291999Y94050D03*
X282800Y87500D03*
X293999Y293550D03*
X284999Y338650D03*
X281499Y338550D03*
X294500Y339000D03*
X279939Y728610D03*
X285499Y745050D03*
X282099D03*
X292999Y743650D03*
X277039Y740300D03*
X282500Y1135000D03*
X295000Y1513000D03*
X289999Y1554650D03*
X293700Y1553351D03*
X276039Y1551300D03*
X283499Y1556050D03*
X279999D03*
X291400Y1561500D03*
X285499Y1930050D03*
X288709Y1948042D03*
X284999Y1947691D03*
X280689Y1942710D03*
X296099Y17100D03*
X305099Y17000D03*
X311400Y17100D03*
X308999Y87050D03*
X297499Y97550D03*
X315800Y100500D03*
X298800Y333000D03*
X301249Y346050D03*
X313039Y352350D03*
X308999Y716450D03*
X315999Y718950D03*
X298000Y743500D03*
X310999Y757050D03*
X314999Y1527550D03*
X297800Y1561600D03*
X312999Y1566050D03*
X310249Y1569800D03*
X313499Y1919050D03*
X310499Y1957050D03*
X315999Y1958550D03*
X317000Y17300D03*
X324800Y89400D03*
X323400Y105200D03*
X326499Y334054D03*
Y337454D03*
X321900Y364600D03*
X327999Y740550D03*
X323249Y749010D03*
X327749Y744050D03*
X324959Y766750D03*
X329499Y801550D03*
X330540Y795509D03*
X320499Y798050D03*
X326500Y1550200D03*
X324000Y1562500D03*
X330300Y1561200D03*
X323999Y1577250D03*
X325221Y1927272D03*
X331622Y1944767D03*
X329999Y1952273D03*
X332103Y1948133D03*
X327100Y1966472D03*
X343499Y31650D03*
X354999Y72050D03*
X343499Y60150D03*
X341499Y63050D03*
Y67110D03*
X357503Y77043D03*
X344520Y406329D03*
X350499Y597300D03*
Y715050D03*
X340699Y1046086D03*
X345499Y1096550D03*
X345424Y1310050D03*
X347324Y1524000D03*
X354500Y1559500D03*
X349774Y1582900D03*
X354000Y1584900D03*
X353499Y1710450D03*
X348499Y1762050D03*
X342999Y1947409D03*
X342621Y1943409D03*
X358999Y61550D03*
X374499Y77550D03*
X365499Y86550D03*
X371999Y549300D03*
X375999Y698550D03*
X371500Y880600D03*
X364499Y1099050D03*
X372999Y1123550D03*
X370149Y1320050D03*
X366149Y1554050D03*
X377900Y1703800D03*
X398799Y36152D03*
X381999Y50150D03*
X382339Y41610D03*
X381999Y53550D03*
X394199Y45050D03*
X381999Y57050D03*
X385999Y78050D03*
X400499Y406329D03*
X394649Y630600D03*
X390999Y1514398D03*
Y1517798D03*
X385499Y1735050D03*
X401499Y80550D03*
X402499Y1476850D03*
X400999Y1575550D03*
X645549Y1815134D03*
X644360Y1819137D03*
X659549Y1810634D03*
X690249Y1805634D03*
X707600Y1815600D03*
X711652Y1822109D03*
X711848Y1825504D03*
X732549Y1806634D03*
X733149Y1798634D03*
X733049Y1814134D03*
X752999Y746842D03*
X757499Y745342D03*
Y1079550D03*
X755600Y1149800D03*
X758499Y1371050D03*
X757999Y1484050D03*
X758199Y1553650D03*
X755000Y1825000D03*
X758499Y1893550D03*
X759114Y1957673D03*
X770999Y302050D03*
Y290050D03*
Y295550D03*
X763571Y295622D03*
X777999Y296050D03*
X772499Y323050D03*
X772873Y326924D03*
X760778Y345050D03*
X768178Y333964D03*
X780499Y330050D03*
X771105Y722789D03*
X766499Y732842D03*
X762999Y734550D03*
X769999Y733050D03*
X771999Y1124550D03*
X772499Y1130050D03*
X779499Y1131050D03*
X767083Y1134550D03*
X768199Y1138590D03*
X774542Y1530050D03*
X774577Y1533796D03*
X771225Y1539474D03*
X767936Y1540336D03*
X774500Y1788000D03*
X770999Y1820550D03*
X771499Y1936550D03*
X767999Y1945173D03*
X764908Y1946592D03*
X771499Y1940050D03*
X785499Y291050D03*
X786978Y298529D03*
X791499Y333050D03*
X789999Y336550D03*
X784499Y334050D03*
X781999Y725550D03*
X788999Y736050D03*
X791999Y733050D03*
X784939Y733550D03*
X792154Y1135926D03*
X784439Y1136550D03*
X789499Y1138050D03*
X784499Y1529050D03*
X784577Y1535628D03*
X791499Y1543550D03*
X793999Y1541050D03*
X788000Y1788000D03*
X793000Y1803500D03*
X795849Y1805500D03*
X791999Y1819050D03*
X783499Y1827050D03*
X802499Y1951550D03*
X800431Y1941193D03*
X785939Y1946800D03*
X792499Y1949050D03*
X794499Y1941050D03*
X782999Y1937050D03*
X802099Y1961950D03*
X820749Y163850D03*
X813249Y163800D03*
X821999Y193116D03*
X809940Y264940D03*
X822100Y261700D03*
Y279500D03*
X816700Y274300D03*
X820600Y664300D03*
X808660Y667540D03*
X813200Y675900D03*
X807000Y1072900D03*
X815400Y1078800D03*
X803199Y1151850D03*
X822100Y1466800D03*
X809960Y1478040D03*
X814700Y1486300D03*
X804899Y1556950D03*
X812000Y1799500D03*
X821249Y1791250D03*
X811000Y1793000D03*
X822499Y1815164D03*
X807000Y1822300D03*
X803500Y1822708D03*
X822700Y1871100D03*
X810900Y1882440D03*
X805900Y1887560D03*
X841499Y135550D03*
X827499Y163550D03*
X839249Y164050D03*
X829917Y216200D03*
X833576Y215432D03*
X837999Y219550D03*
X842499Y280924D03*
X827500Y274500D03*
X836500Y274950D03*
X827499Y313424D03*
X829800Y666650D03*
X835150Y677650D03*
X825700Y1083100D03*
X825800Y1072300D03*
X827700Y1487600D03*
X836625Y1487400D03*
X828500Y1877800D03*
X834799Y1946950D03*
X861999Y146550D03*
X854400Y264600D03*
X847878Y250040D03*
X851278Y249974D03*
X847450Y246666D03*
X850999Y246550D03*
X858478Y274050D03*
X865499Y288050D03*
X851172Y655432D03*
X847772Y655370D03*
X851197Y652032D03*
X847493Y651981D03*
X852696Y671197D03*
X850833Y1061441D03*
X847233Y1061492D03*
X847355Y1058094D03*
X851042Y1058047D03*
X852333Y1077716D03*
X860133Y1084142D03*
X864499Y1128750D03*
X860799Y1358925D03*
X861849Y1376050D03*
X848888Y1466402D03*
X852288Y1466346D03*
X848861Y1462463D03*
X852429Y1462948D03*
X854327Y1477550D03*
X858827Y1485696D03*
X863699Y1501250D03*
X862800Y1712700D03*
X851500Y1821400D03*
X849375Y1824982D03*
X854905Y1825583D03*
X853499Y1871036D03*
X850099Y1871056D03*
X854480Y1867578D03*
X849999Y1867550D03*
X863788Y1866953D03*
X865501Y1858747D03*
X859314Y1891365D03*
X854814Y1883550D03*
X863699Y1906450D03*
X857099Y1917650D03*
X882499Y147050D03*
X867500Y163924D03*
X867576Y159924D03*
X878078Y240103D03*
Y243878D03*
X874928Y238822D03*
X874790Y244748D03*
X871999Y283924D03*
X872136Y273924D03*
X886600Y303924D03*
X868799Y294750D03*
X867899Y321550D03*
X886200Y313924D03*
X868299Y336150D03*
X879750Y570550D03*
X879950Y565050D03*
X878596Y645573D03*
X874999Y644550D03*
X878596Y649348D03*
X875270Y650059D03*
X883083Y979183D03*
X879708Y971892D03*
X878233Y1051095D03*
X877964Y1054485D03*
X874733Y1055792D03*
X874999Y1049550D03*
X872086Y1084948D03*
X871999Y1094948D03*
X871499Y1124948D03*
X872086Y1114948D03*
X866700Y1379796D03*
X866596Y1375796D03*
X878054Y1456450D03*
X877853Y1459991D03*
X874499Y1460550D03*
X874986Y1454983D03*
X872086Y1490460D03*
X871999Y1500460D03*
Y1520460D03*
X872086Y1530460D03*
X867523Y1542821D03*
X867199Y1535150D03*
X886439Y1717600D03*
X873800Y1733600D03*
X879700Y1786300D03*
X879664Y1782213D03*
X866914Y1861840D03*
Y1865615D03*
X871921Y1905972D03*
X871421Y1895972D03*
X872086Y1925972D03*
Y1935972D03*
X901499Y92050D03*
X897555Y90494D03*
X898999Y99050D03*
X902499Y110550D03*
X898999D03*
X907499Y131800D03*
X896999Y141550D03*
X902999Y556050D03*
X900499Y962100D03*
X900999Y979050D03*
X889800Y1711500D03*
X923761Y85550D03*
X928561Y95181D03*
X928428Y83714D03*
X928508Y87747D03*
X928561Y91481D03*
X928457Y79885D03*
X928461Y75981D03*
X916499Y115050D03*
X926999D03*
Y122050D03*
X910999Y124550D03*
X916499Y172550D03*
X922049Y574375D03*
Y978575D03*
X921549Y1788475D03*
X917499Y1796550D03*
X932961Y85581D03*
X943499Y82550D03*
X930999Y115550D03*
X938499D03*
X946899Y122550D03*
X937999Y122050D03*
X934499Y118750D03*
X939549Y175175D03*
X961499Y93350D03*
X958999Y96050D03*
X961499Y100050D03*
X966499Y552050D03*
X965999Y954550D03*
X965150Y1639500D03*
X961702Y1636102D03*
X969600Y1638300D03*
X967600Y1651100D03*
X971558Y1646500D03*
X981200Y1618002D03*
X986400Y1639302D03*
X987100Y1624900D03*
X981200Y1625800D03*
X990425Y1633898D03*
X987029Y1634075D03*
X977500Y1660500D03*
X989502Y1646000D03*
X988800Y1658300D03*
X981500Y1653000D03*
X980800Y1659600D03*
X982050Y1649302D03*
X978000Y1668000D03*
X989000Y1663802D03*
X987200Y1675600D03*
X989900Y1678800D03*
X974000Y1670700D03*
X984211Y1667500D03*
X1234250Y1714050D03*
G54D15*
X68898Y17047D03*
Y190275D03*
Y422559D03*
Y595787D03*
Y828071D03*
Y1001299D03*
Y1233583D03*
Y1406811D03*
Y1639095D03*
Y1812323D03*
X167323Y179803D03*
Y353031D03*
Y585315D03*
Y758543D03*
Y990827D03*
Y1164055D03*
Y1396339D03*
Y1569567D03*
Y1801851D03*
Y1975079D03*
X895669Y179803D03*
Y353031D03*
Y585315D03*
Y758543D03*
Y990827D03*
Y1164055D03*
Y1396339D03*
Y1569567D03*
Y1801851D03*
Y1975079D03*
X1234250Y1489250D03*
G54D16*
X78150Y28858D03*
Y178464D03*
Y434370D03*
Y583976D03*
Y839882D03*
Y989488D03*
Y1245394D03*
Y1395000D03*
Y1650906D03*
Y1800512D03*
X158071Y191614D03*
Y341220D03*
Y597126D03*
Y746732D03*
Y1002638D03*
Y1152244D03*
Y1408150D03*
Y1557756D03*
Y1813662D03*
Y1963268D03*
X886417Y191614D03*
Y341220D03*
Y597126D03*
Y746732D03*
Y1002638D03*
Y1152244D03*
Y1408150D03*
Y1557756D03*
Y1813662D03*
Y1963268D03*
X1234250Y1601650D03*
G54D17*
X129921Y17716D03*
X994093Y1889751D03*
X1234250Y1629750D03*
G54D18*
X1019291Y1416024D03*
Y1694212D03*
X1234250Y1517350D03*
G54D19*
G01X-78740Y15000D02*
G03X-63740Y0I15000J0D01*
G01X-78740Y15000D02*
Y319646D01*
G01X-63740Y334646D02*
G03X-78740Y319646I0J-15000D01*
G01Y908315D02*
G03X-63740Y893315I15000J0D01*
G01X-78740Y908315D02*
Y1304286D01*
G01X-63740Y1319286D02*
G03X-78740Y1304286I0J-15000D01*
G01Y1892953D02*
G03X-63740Y1877953I15000J0D01*
G01X-78740Y1892953D02*
Y1977126D01*
G01X-63740Y1992126D02*
G03X-78740Y1977126I0J-15000D01*
G01X-7874Y0D02*
X-63740D01*
G01X-7874Y334646D02*
X-63740D01*
G01X-7874Y893315D02*
X-63740D01*
G01X-7874Y1319286D02*
X-63740D01*
G01X-7874Y1877953D02*
X-63740D01*
G01X-7874Y1992126D02*
X-63740D01*
G01X-7874Y17253D02*
Y0D01*
G01X0Y17214D02*
G03X-7874I-3937J0D01*
G01Y41772D02*
Y167110D01*
G01Y41772D02*
G03X0I3937J0D01*
G01Y167110D02*
G03X-7874I-3937J0D01*
G01Y191667D02*
Y308383D01*
G01Y191667D02*
G03X0I3937J0D01*
G01Y308383D02*
G03X-7874I-3937J0D01*
G01Y331986D02*
Y334646D01*
G01Y332003D02*
G03X0I3937J0D01*
G01X-7874Y905988D02*
Y893315D01*
G01X0Y905988D02*
G03X-7874I-3937J0D01*
G01Y1106301D02*
Y933234D01*
G01D02*
G03X0I3937J0D01*
G01Y1106301D02*
G03X-7874I-3937J0D01*
G01Y1280567D02*
Y1129921D01*
G01D02*
G03X0I3937J0D01*
G01Y1280567D02*
G03X-7874I-3937J0D01*
G01Y1309889D02*
Y1319286D01*
G01Y1309889D02*
G03X0I3937J0D01*
G01X-7874Y1889223D02*
Y1877953D01*
G01X0Y1889223D02*
G03X-7874I-3937J0D01*
G01X0D02*
G03X-7874I-3937J0D01*
G01Y1912843D02*
Y1962927D01*
G01Y1912843D02*
G03X0I3937J0D01*
G01Y1962927D02*
G03X-7874I-3937J0D01*
G01X0D02*
G03X-7874I-3937J0D01*
G01Y1986547D02*
Y1992126D01*
G01Y1986547D02*
G03X0I3937J0D01*
G01X3937Y0D02*
X1029528D01*
G01X0Y3937D02*
G03X3937Y0I3937J0D01*
G01X0Y409646D02*
Y3937D01*
G01X3937Y413583D02*
X0Y409646D01*
G01X19882Y413583D02*
X3937D01*
G01Y421063D02*
X19882D01*
G01X0Y425000D02*
X3937Y421063D01*
G01X0Y819094D02*
Y425000D01*
G01X3937Y823031D02*
X0Y819094D01*
G01X19882Y823031D02*
X3937D01*
G01Y830512D02*
X19882D01*
G01X0Y834449D02*
X3937Y830512D01*
G01X0Y1393898D02*
Y834449D01*
G01X3937Y1397835D02*
X0Y1393898D01*
G01X19882Y1397835D02*
X3937D01*
G01Y1405315D02*
X19882D01*
G01X0Y1409252D02*
X3937Y1405315D01*
G01X0Y1803346D02*
Y1409252D01*
G01X3937Y1807283D02*
X0Y1803346D01*
G01X19882Y1807283D02*
X3937D01*
G01Y1814764D02*
X19882D01*
G01X0Y1818701D02*
X3937Y1814764D01*
G01X0Y1988189D02*
Y1818701D01*
G01X3937Y1992126D02*
G03X0Y1988189I0J-3937D01*
G01X1029528Y1992126D02*
X3937D01*
G01X19882Y413583D02*
G03Y421063I0J3740D01*
G01Y823031D02*
G03Y830512I0J3741D01*
G01Y1397835D02*
G03Y1405315I0J3740D01*
G01Y1807283D02*
G03Y1814764I0J3740D01*
G01X989744Y1616083D02*
X1015354D01*
G01X989744D02*
G03Y1611870I0J-2107D01*
G01X1015354D02*
X989744D01*
G01X1033465Y3937D02*
Y1424882D01*
G01X1029528Y0D02*
G03X1033465Y3937I0J3937D01*
G01X1041338Y24677D02*
G03X1033464I-3937J0D01*
G01X1041338D02*
G03X1033464I-3937J0D01*
G01Y48297D02*
G03X1041338I3937J0D01*
G01Y217343D02*
G03X1033464I-3937J0D01*
G01X1041338D02*
G03X1033464I-3937J0D01*
G01Y240964D02*
G03X1041338I3937J0D01*
G01X1033464D02*
G03X1041338I3937J0D01*
G01Y445039D02*
G03X1033464I-3937J0D01*
G01X1041338D02*
G03X1033464I-3937J0D01*
G01Y468659D02*
G03X1041338I3937J0D01*
G01X1033464D02*
G03X1041338I3937J0D01*
G01Y697473D02*
G03X1033464I-3937J0D01*
G01X1041338D02*
G03X1033464I-3937J0D01*
G01Y721093D02*
G03X1041338I3937J0D01*
G01X1033464D02*
G03X1041338I3937J0D01*
G01Y996852D02*
G03X1033464I-3937J0D01*
G01X1041338D02*
G03X1033464I-3937J0D01*
G01Y1020472D02*
G03X1041338I3937J0D01*
G01X1033464D02*
G03X1041338I3937J0D01*
G01Y1344060D02*
G03X1033464I-3937J0D01*
G01X1041338D02*
G03X1033464I-3937J0D01*
G01Y1367680D02*
G03X1041338I3937J0D01*
G01X1033464D02*
G03X1041338I3937J0D01*
G01X1033465Y1424882D02*
X1029528Y1428819D01*
G01X1019291Y1433740D02*
Y1607933D01*
G01Y1433740D02*
G03X1024213Y1428819I4921J0D01*
G01X1029528D02*
X1024213D01*
G01X1015354Y1616083D02*
X1019291Y1620020D01*
G01Y1607933D02*
X1015354Y1611870D01*
G01X1019291Y1620020D02*
Y1676496D01*
G01X1029528Y1681417D02*
X1033465Y1685354D01*
G01X1024213Y1681417D02*
G03X1019291Y1676496I-1J-4921D01*
G01X1033465Y1685354D02*
Y1988189D01*
G01X1024213Y1681417D02*
X1029528D01*
G01X1041338Y1739719D02*
G03X1033464I-3937J0D01*
G01X1041338D02*
G03X1033464I-3937J0D01*
G01Y1763339D02*
G03X1041338I3937J0D01*
G01X1033464D02*
G03X1041338I3937J0D01*
G01Y1959242D02*
G03X1033464I-3937J0D01*
G01X1041338D02*
G03X1033464I-3937J0D01*
G01X1033465Y1988189D02*
G03X1029528Y1992126I-3937J0D01*
G01X1033464Y1982862D02*
G03X1041338I3937J0D01*
G01Y24677D02*
Y0D01*
G01D02*
X1097205D01*
G01X1041338Y217343D02*
Y48297D01*
G01Y445039D02*
Y240964D01*
G01Y697473D02*
Y468601D01*
G01Y996852D02*
Y721093D01*
G01Y1344060D02*
Y1020472D01*
G01Y1367680D02*
Y1393701D01*
G01D02*
X1097205D01*
G01X1041338Y1733129D02*
Y1716536D01*
G01X1065043D02*
X1041338D01*
G01Y1739719D02*
Y1731536D01*
G01Y1959242D02*
Y1763310D01*
G01Y1992126D02*
X1097205D01*
G01X1041338Y1982862D02*
Y1992126D01*
G01X1056338Y1716536D02*
X1097205D01*
G01Y0D02*
G03X1112205Y15000I0J15000D01*
G01Y1378701D02*
G03X1097205Y1393701I-15000J0D01*
G01Y1716536D02*
G03X1112205Y1731536I0J15000D01*
G01Y1977126D02*
G03X1097205Y1992126I-15000J0D01*
G01X1112205Y648419D02*
Y15000D01*
G01Y656293D02*
G03Y648419I0J-3937D01*
G01Y1378701D02*
Y656293D01*
G01Y1977126D02*
Y1731536D01*
M02*
